G04 ================== begin FILE IDENTIFICATION RECORD ==================*
G04 Layout Name:  12004-1.brd*
G04 Film Name:    BSILK*
G04 File Format:  Gerber RS274X*
G04 File Origin:  Cadence Allegro 16.2-S033*
G04 Origin Date:  Tue Oct 16 14:35:46 2012*
G04 *
G04 Layer:  VIA CLASS/FILMMASKBOTTOM*
G04 Layer:  REF DES/ASSEMBLY_BOTTOM*
G04 Layer:  PACKAGE GEOMETRY/SILKSCREEN_BOTTOM*
G04 Layer:  DRAWING FORMAT/LAYER_PCB_STORY*
G04 Layer:  DRAWING FORMAT/LAYER_SILK_B*
G04 Layer:  BOARD GEOMETRY/SILKSCREEN_BOTTOM*
G04 *
G04 Offset:    (0.00 0.00)*
G04 Mirror:    No*
G04 Mode:      Positive*
G04 Rotation:  0*
G04 FullContactRelief:  No*
G04 UndefLineWidth:     6.00*
G04 ================== end FILE IDENTIFICATION RECORD ====================*
%FSLAX35Y35*MOIN*%
%IR0*IPPOS*OFA0.00000B0.00000*MIA0B0*SFA1.00000B1.00000*%
%ADD10C,.032*%
%ADD11C,.02*%
%ADD12C,.012*%
%ADD13C,.013*%
%ADD14C,.025*%
%ADD15C,.0005*%
%ADD16C,.005*%
%ADD17C,.006*%
%ADD18C,.008*%
G75*
%LPD*%
G75*
G36*
G01X33844Y295417D02*
X24844D01*
Y287417D01*
X33844D01*
Y295417D01*
G37*
G36*
G01X82563Y292683D02*
X157363D01*
Y241483D01*
X82563D01*
Y292683D01*
G37*
G36*
G01X167963Y240383D02*
X158163Y230583D01*
X167963D01*
Y240383D01*
G37*
G36*
G01X405375Y439474D02*
Y444474D01*
X410375Y439474D01*
X405375D01*
G37*
G36*
G01X683958Y449320D02*
Y444320D01*
X688958D01*
X683958Y449320D01*
G37*
G36*
G01X686525Y522891D02*
X695525D01*
Y530891D01*
X686525D01*
Y522891D01*
G37*
G36*
G01X653850Y544605D02*
X662850D01*
Y552605D01*
X653850D01*
Y544605D01*
G37*
G36*
G01X720642Y549183D02*
X711642D01*
Y541183D01*
X720642D01*
Y549183D01*
G37*
G54D10*
X169800Y155796D03*
X165162Y155909D03*
X169709Y160049D03*
X165388Y160094D03*
X225919Y88394D03*
X225937Y80731D03*
X221710Y80767D03*
X221722Y88431D03*
X230158Y88359D03*
X230123Y80805D03*
X225851Y73774D03*
X221740Y73844D03*
X229870Y73970D03*
X668135Y523360D03*
X672161Y528021D03*
X676550Y523677D03*
X672342Y519560D03*
X672257Y523769D03*
G54D11*
G01X-771361Y-182763D02*
Y-262763D01*
G01Y-218263D02*
X373639D01*
G01X-771361Y-262763D02*
X373639D01*
G01X-775361Y-166763D02*
G02I-12000J0D01*
G01X-780511D02*
G02I-6850J0D01*
G01X-787361Y-182763D02*
Y-150763D01*
G01X-771361Y-166763D02*
X-803361D01*
G01X-771361Y-182763D02*
X373639D01*
G01X-413861D02*
Y-262763D01*
G01X-276361Y-182763D02*
Y-262763D01*
G01X-161361Y-182763D02*
Y-262763D01*
G01X6139Y-182763D02*
Y-262763D01*
G01X78376Y310864D02*
X73376D01*
G01X48299Y496166D02*
X53299D01*
G01X176139Y-182763D02*
Y-262763D01*
G01X176308Y235787D02*
Y240787D01*
G01X373639Y-182763D02*
Y-262763D01*
G01X401639Y-166763D02*
G02I-12000J0D01*
G01X396489D02*
G02I-6850J0D01*
G01X389639Y-182763D02*
Y-150763D01*
G01X405639Y-166763D02*
X373639D01*
G01X403434Y450186D02*
X398434D01*
G01X395610Y450229D02*
X390610D01*
G01X676009Y480923D02*
Y475923D01*
G54D12*
G01X-955512Y0D02*
X-986221D01*
G01X-955512D02*
X-986221D01*
G01X-996063Y70079D02*
Y39370D01*
G01Y708662D02*
Y739370D01*
G01X-986221Y925197D02*
X-955512D01*
G01X-986221D02*
X-955512D01*
G01X-769685Y0D02*
X-738977D01*
G01X-769685D02*
X-738977D01*
G01X-750000Y925197D02*
X-719292D01*
G01X-492126Y0D02*
X-522835D01*
G01X-492126D02*
X-522835D01*
G01X-482599Y925097D02*
X-513307D01*
G01X-334646Y0D02*
X-365355D01*
G01X-334646D02*
X-365355D01*
G01X-334646D02*
X-365355D01*
G01X-285248Y925097D02*
X-315957D01*
G01X-260630Y137796D02*
X-244882D01*
G01X-143740Y262205D02*
Y292914D01*
G01X-177221Y467569D02*
Y436860D01*
G01X-92481Y662992D02*
Y632284D01*
G01X-59000Y488137D02*
Y457429D01*
G01X61819Y0D02*
X31111D01*
G01X8661Y787402D02*
X24409D01*
G01X119291Y925197D02*
X88582D01*
G01X267031Y-100D02*
X297740D01*
G01X335827Y925197D02*
X305118D01*
G01X483071Y0D02*
X513779D01*
G01X522441Y925197D02*
X553149D01*
G01X719291Y0D02*
X750000D01*
G01X759842Y216536D02*
Y185827D01*
G01Y885827D02*
Y855118D01*
G01Y885827D02*
Y855118D01*
G01X719291Y925197D02*
X750000D01*
G54D13*
G01X64455Y177814D02*
X68855D01*
Y181314D01*
G01X55384Y195671D02*
X59784D01*
Y199171D01*
G01X64053Y523448D02*
Y527848D01*
X60553D01*
G01X60715Y542648D02*
Y547048D01*
X57215D01*
G54D14*
G01X35844Y287317D02*
Y279717D01*
G01X684525Y530991D02*
Y538591D01*
G01X651850Y552705D02*
Y560305D01*
G01X722642Y541083D02*
Y533483D01*
G54D15*
G01X65907Y177826D02*
X65804D01*
G01X65982Y177751D02*
X65729D01*
G01X66057Y177676D02*
X65654D01*
G01X66132Y177601D02*
X65579D01*
G01X66207Y177526D02*
X65504D01*
G01X66282Y177451D02*
X65429D01*
G01X66357Y177376D02*
X65354D01*
G01X66432Y177301D02*
X65279D01*
G01X66507Y177226D02*
X65204D01*
G01X66582Y177151D02*
X65129D01*
G01X66657Y177076D02*
X65054D01*
G01X66732Y177001D02*
X64979D01*
G01X66807Y176926D02*
X64904D01*
G01X66882Y176851D02*
X64829D01*
G01X64786Y176767D02*
X66939Y176784D01*
G01X66992Y176741D02*
X65855Y177879D01*
G01D02*
X64716Y176739D01*
G01X64775D02*
X66935D01*
G01X66991D02*
X64716D01*
G01X66919Y176814D02*
X64791D01*
G01X66844Y176889D02*
X64866D01*
G01X66769Y176964D02*
X64941D01*
G01X66694Y177039D02*
X65016D01*
G01X66619Y177114D02*
X65091D01*
G01X66544Y177189D02*
X65166D01*
G01X66469Y177264D02*
X65241D01*
G01X66394Y177339D02*
X65316D01*
G01X66319Y177414D02*
X65391D01*
G01X66244Y177489D02*
X65466D01*
G01X66169Y177564D02*
X65541D01*
G01X66094Y177639D02*
X65616D01*
G01X66019Y177714D02*
X65691D01*
G01X65944Y177789D02*
X65766D01*
G01X65869Y177864D02*
X65841D01*
G01X56836Y195683D02*
X56733D01*
G01X56911Y195608D02*
X56658D01*
G01X56986Y195533D02*
X56583D01*
G01X57061Y195458D02*
X56508D01*
G01X57136Y195383D02*
X56433D01*
G01X57211Y195308D02*
X56358D01*
G01X57286Y195233D02*
X56283D01*
G01X57361Y195158D02*
X56208D01*
G01X57436Y195083D02*
X56133D01*
G01X57511Y195008D02*
X56058D01*
G01X57586Y194933D02*
X55983D01*
G01X57661Y194858D02*
X55908D01*
G01X57736Y194783D02*
X55833D01*
G01X57811Y194708D02*
X55758D01*
G01X55715Y194624D02*
X57868Y194641D01*
G01X57921Y194598D02*
X56784Y195736D01*
G01D02*
X55645Y194596D01*
G01X55704D02*
X57864D01*
G01X57920D02*
X55645D01*
G01X57848Y194671D02*
X55720D01*
G01X57773Y194746D02*
X55795D01*
G01X57698Y194821D02*
X55870D01*
G01X57623Y194896D02*
X55945D01*
G01X57548Y194971D02*
X56020D01*
G01X57473Y195046D02*
X56095D01*
G01X57398Y195121D02*
X56170D01*
G01X57323Y195196D02*
X56245D01*
G01X57248Y195271D02*
X56320D01*
G01X57173Y195346D02*
X56395D01*
G01X57098Y195421D02*
X56470D01*
G01X57023Y195496D02*
X56545D01*
G01X56948Y195571D02*
X56620D01*
G01X56873Y195646D02*
X56695D01*
G01X56798Y195721D02*
X56770D01*
G01X64041Y524900D02*
Y524797D01*
G01X64116Y524975D02*
Y524722D01*
G01X64191Y525050D02*
Y524647D01*
G01X64266Y525125D02*
Y524572D01*
G01X64341Y525200D02*
Y524497D01*
G01X64416Y525275D02*
Y524422D01*
G01X64491Y525350D02*
Y524347D01*
G01X64566Y525425D02*
Y524272D01*
G01X64641Y525500D02*
Y524197D01*
G01X64716Y525575D02*
Y524122D01*
G01X64791Y525650D02*
Y524047D01*
G01X64866Y525725D02*
Y523972D01*
G01X64941Y525800D02*
Y523897D01*
G01X65016Y525875D02*
Y523822D01*
G01X65100Y523779D02*
X65083Y525932D01*
G01X65126Y525985D02*
X63988Y524848D01*
G01D02*
X65128Y523709D01*
G01Y523768D02*
Y525928D01*
G01Y525984D02*
Y523709D01*
G01X65053Y525912D02*
Y523784D01*
G01X64978Y525837D02*
Y523859D01*
G01X64903Y525762D02*
Y523934D01*
G01X64828Y525687D02*
Y524009D01*
G01X64753Y525612D02*
Y524084D01*
G01X64678Y525537D02*
Y524159D01*
G01X64603Y525462D02*
Y524234D01*
G01X64528Y525387D02*
Y524309D01*
G01X64453Y525312D02*
Y524384D01*
G01X64378Y525237D02*
Y524459D01*
G01X64303Y525162D02*
Y524534D01*
G01X64228Y525087D02*
Y524609D01*
G01X64153Y525012D02*
Y524684D01*
G01X64078Y524937D02*
Y524759D01*
G01X64003Y524862D02*
Y524834D01*
G01X60703Y544100D02*
Y543997D01*
G01X60778Y544175D02*
Y543922D01*
G01X60853Y544250D02*
Y543847D01*
G01X60928Y544325D02*
Y543772D01*
G01X61003Y544400D02*
Y543697D01*
G01X61078Y544475D02*
Y543622D01*
G01X61153Y544550D02*
Y543547D01*
G01X61228Y544625D02*
Y543472D01*
G01X61303Y544700D02*
Y543397D01*
G01X61378Y544775D02*
Y543322D01*
G01X61453Y544850D02*
Y543247D01*
G01X61528Y544925D02*
Y543172D01*
G01X61603Y545000D02*
Y543097D01*
G01X61678Y545075D02*
Y543022D01*
G01X61762Y542979D02*
X61745Y545132D01*
G01X61788Y545185D02*
X60650Y544048D01*
G01D02*
X61790Y542909D01*
G01Y542968D02*
Y545128D01*
G01Y545184D02*
Y542909D01*
G01X61715Y545112D02*
Y542984D01*
G01X61640Y545037D02*
Y543059D01*
G01X61565Y544962D02*
Y543134D01*
G01X61490Y544887D02*
Y543209D01*
G01X61415Y544812D02*
Y543284D01*
G01X61340Y544737D02*
Y543359D01*
G01X61265Y544662D02*
Y543434D01*
G01X61190Y544587D02*
Y543509D01*
G01X61115Y544512D02*
Y543584D01*
G01X61040Y544437D02*
Y543659D01*
G01X60965Y544362D02*
Y543734D01*
G01X60890Y544287D02*
Y543809D01*
G01X60815Y544212D02*
Y543884D01*
G01X60740Y544137D02*
Y543959D01*
G01X60665Y544062D02*
Y544034D01*
G54D16*
G01X20970Y302150D02*
Y299650D01*
G01X21928Y302150D02*
X20012D01*
G01X18803Y299650D02*
Y302150D01*
X17803D01*
X17470Y302025D01*
X17220Y301733D01*
X17137Y301400D01*
X17220Y301067D01*
X17428Y300817D01*
X17803Y300692D01*
X18803D01*
G01X14970Y299650D02*
Y302150D01*
X15470Y301650D01*
G01Y299650D02*
X14470D01*
G01X12762Y300692D02*
X12470Y300983D01*
X12220Y301150D01*
X11887Y301233D01*
X11595Y301150D01*
X11387Y300983D01*
X11220Y300733D01*
X11178Y300442D01*
X11220Y300192D01*
X11387Y299942D01*
X11637Y299733D01*
X11928Y299650D01*
X12262Y299733D01*
X12553Y299983D01*
X12720Y300358D01*
X12762Y300775D01*
X12678Y301317D01*
X12553Y301608D01*
X12345Y301900D01*
X12053Y302108D01*
X11762Y302150D01*
X11470Y302067D01*
X11262Y301858D01*
G01X8470Y299650D02*
Y302150D01*
X10012Y300358D01*
X7928D01*
G01X20200Y491000D02*
Y488500D01*
G01X21158Y491000D02*
X19242D01*
G01X18033Y488500D02*
Y491000D01*
X17033D01*
X16700Y490875D01*
X16450Y490583D01*
X16367Y490250D01*
X16450Y489917D01*
X16658Y489667D01*
X17033Y489542D01*
X18033D01*
G01X14200Y488500D02*
Y491000D01*
X14700Y490500D01*
G01Y488500D02*
X13700D01*
G01X11992Y490583D02*
X11742Y490833D01*
X11450Y490958D01*
X11117Y491000D01*
X10700Y490917D01*
X10408Y490708D01*
X10325Y490458D01*
X10367Y490208D01*
X10533Y490000D01*
X11367Y489583D01*
X11742Y489292D01*
X11992Y488875D01*
X12075Y488500D01*
X10325D01*
G01X8200Y491000D02*
X8533Y490917D01*
X8783Y490708D01*
X8950Y490458D01*
X9075Y490125D01*
X9117Y489750D01*
X9075Y489375D01*
X8950Y489042D01*
X8783Y488792D01*
X8533Y488583D01*
X8200Y488500D01*
X7867Y488583D01*
X7617Y488792D01*
X7450Y489042D01*
X7325Y489375D01*
X7283Y489750D01*
X7325Y490125D01*
X7450Y490458D01*
X7617Y490708D01*
X7867Y490917D01*
X8200Y491000D01*
G01X70733Y130000D02*
Y132500D01*
X69733D01*
X69400Y132375D01*
X69150Y132083D01*
X69067Y131750D01*
X69150Y131417D01*
X69358Y131167D01*
X69733Y131042D01*
X70733D01*
G01X66900Y130000D02*
X67233Y130042D01*
X67525Y130208D01*
X67775Y130458D01*
X67942Y130750D01*
X68025Y131083D01*
Y131417D01*
X67942Y131750D01*
X67775Y132042D01*
X67525Y132292D01*
X67233Y132458D01*
X66900Y132500D01*
X66567Y132458D01*
X66275Y132292D01*
X66025Y132042D01*
X65858Y131750D01*
X65775Y131417D01*
Y131083D01*
X65858Y130750D01*
X66025Y130458D01*
X66275Y130208D01*
X66567Y130042D01*
X66900Y130000D01*
G01X66567Y130667D02*
X66067Y130000D01*
G01X64817Y130500D02*
X64567Y130208D01*
X64233Y130042D01*
X63858Y130000D01*
X63525Y130042D01*
X63192Y130250D01*
X62983Y130500D01*
X62942Y130750D01*
X63025Y131042D01*
X63317Y131250D01*
X63608Y131333D01*
X63983D01*
G01X63608D02*
X63358Y131458D01*
X63150Y131667D01*
X63067Y131917D01*
X63150Y132167D01*
X63358Y132375D01*
X63733Y132500D01*
X64108Y132458D01*
X64483Y132292D01*
G01X55292Y95717D02*
X55417Y95467D01*
X55500Y95175D01*
Y94842D01*
X55375Y94467D01*
X55167Y94175D01*
X54917Y93967D01*
X54500Y93800D01*
X54125Y93758D01*
X53750Y93842D01*
X53500Y93967D01*
X53250Y94217D01*
X53083Y94508D01*
X53000Y94800D01*
Y95092D01*
X53083Y95383D01*
X53208Y95633D01*
X53375Y95842D01*
G01X55083Y97008D02*
X55333Y97258D01*
X55458Y97550D01*
X55500Y97883D01*
X55417Y98300D01*
X55208Y98592D01*
X54958Y98675D01*
X54708Y98633D01*
X54500Y98467D01*
X54083Y97633D01*
X53792Y97258D01*
X53375Y97008D01*
X53000Y96925D01*
Y98675D01*
G01X53375Y99883D02*
X53167Y100133D01*
X53042Y100425D01*
X53000Y100800D01*
X53083Y101175D01*
X53250Y101467D01*
X53542Y101675D01*
X53875Y101717D01*
X54208Y101633D01*
X54417Y101425D01*
X54583Y101133D01*
X54625Y100842D01*
X54583Y100550D01*
X54417Y100175D01*
X55500Y100300D01*
Y101425D01*
G01X53500Y102883D02*
X53208Y103133D01*
X53042Y103467D01*
X53000Y103842D01*
X53042Y104175D01*
X53250Y104508D01*
X53500Y104717D01*
X53750Y104758D01*
X54042Y104675D01*
X54250Y104383D01*
X54333Y104092D01*
Y103717D01*
G01Y104092D02*
X54458Y104342D01*
X54667Y104550D01*
X54917Y104633D01*
X55167Y104550D01*
X55375Y104342D01*
X55500Y103967D01*
X55458Y103592D01*
X55292Y103217D01*
G01X63192Y95417D02*
X63317Y95167D01*
X63400Y94875D01*
Y94542D01*
X63275Y94167D01*
X63067Y93875D01*
X62817Y93667D01*
X62400Y93500D01*
X62025Y93458D01*
X61650Y93542D01*
X61400Y93667D01*
X61150Y93917D01*
X60983Y94208D01*
X60900Y94500D01*
Y94792D01*
X60983Y95083D01*
X61108Y95333D01*
X61275Y95542D01*
G01X62983Y96708D02*
X63233Y96958D01*
X63358Y97250D01*
X63400Y97583D01*
X63317Y98000D01*
X63108Y98292D01*
X62858Y98375D01*
X62608Y98333D01*
X62400Y98167D01*
X61983Y97333D01*
X61692Y96958D01*
X61275Y96708D01*
X60900Y96625D01*
Y98375D01*
G01Y101000D02*
X63400D01*
X61608Y99458D01*
Y101542D01*
G01X61192Y102792D02*
X60983Y103083D01*
X60900Y103417D01*
X60983Y103750D01*
X61233Y104042D01*
X61608Y104250D01*
X61983Y104333D01*
X62442D01*
X62817Y104250D01*
X63150Y104042D01*
X63317Y103792D01*
X63400Y103500D01*
X63317Y103167D01*
X63150Y102917D01*
X62900Y102750D01*
X62567Y102667D01*
X62275Y102750D01*
X61983Y102958D01*
X61817Y103208D01*
X61775Y103500D01*
X61858Y103833D01*
X62067Y104083D01*
X62442Y104333D01*
G01X74069Y73876D02*
X76569D01*
Y74917D01*
X76444Y75251D01*
X76277Y75459D01*
X75944Y75542D01*
X75611Y75459D01*
X75402Y75209D01*
X75277Y74917D01*
Y73876D01*
G01Y74917D02*
X74069Y75542D01*
G01X76152Y76917D02*
X76402Y77167D01*
X76527Y77459D01*
X76569Y77792D01*
X76486Y78209D01*
X76277Y78501D01*
X76027Y78584D01*
X75777Y78542D01*
X75569Y78376D01*
X75152Y77542D01*
X74861Y77167D01*
X74444Y76917D01*
X74069Y76834D01*
Y78584D01*
G01X76152Y79917D02*
X76402Y80167D01*
X76527Y80459D01*
X76569Y80792D01*
X76486Y81209D01*
X76277Y81501D01*
X76027Y81584D01*
X75777Y81542D01*
X75569Y81376D01*
X75152Y80542D01*
X74861Y80167D01*
X74444Y79917D01*
X74069Y79834D01*
Y81584D01*
G01X75111Y82917D02*
X75402Y83209D01*
X75569Y83459D01*
X75652Y83792D01*
X75569Y84084D01*
X75402Y84292D01*
X75152Y84459D01*
X74861Y84501D01*
X74611Y84459D01*
X74361Y84292D01*
X74152Y84042D01*
X74069Y83751D01*
X74152Y83417D01*
X74402Y83126D01*
X74777Y82959D01*
X75194Y82917D01*
X75736Y83001D01*
X76027Y83126D01*
X76319Y83334D01*
X76527Y83626D01*
X76569Y83917D01*
X76486Y84209D01*
X76277Y84417D01*
G01X39733Y187100D02*
Y189600D01*
X38692D01*
X38358Y189475D01*
X38150Y189308D01*
X38067Y188975D01*
X38150Y188642D01*
X38400Y188433D01*
X38692Y188308D01*
X39733D01*
G01X38692D02*
X38067Y187100D01*
G01X36692Y189183D02*
X36442Y189433D01*
X36150Y189558D01*
X35817Y189600D01*
X35400Y189517D01*
X35108Y189308D01*
X35025Y189058D01*
X35067Y188808D01*
X35233Y188600D01*
X36067Y188183D01*
X36442Y187892D01*
X36692Y187475D01*
X36775Y187100D01*
X35025D01*
G01X33692Y189183D02*
X33442Y189433D01*
X33150Y189558D01*
X32817Y189600D01*
X32400Y189517D01*
X32108Y189308D01*
X32025Y189058D01*
X32067Y188808D01*
X32233Y188600D01*
X33067Y188183D01*
X33442Y187892D01*
X33692Y187475D01*
X33775Y187100D01*
X32025D01*
G01X29900Y189600D02*
X30233Y189517D01*
X30483Y189308D01*
X30650Y189058D01*
X30775Y188725D01*
X30817Y188350D01*
X30775Y187975D01*
X30650Y187642D01*
X30483Y187392D01*
X30233Y187183D01*
X29900Y187100D01*
X29567Y187183D01*
X29317Y187392D01*
X29150Y187642D01*
X29025Y187975D01*
X28983Y188350D01*
X29025Y188725D01*
X29150Y189058D01*
X29317Y189308D01*
X29567Y189517D01*
X29900Y189600D01*
G01X74333Y148200D02*
Y150700D01*
X73333D01*
X73000Y150575D01*
X72750Y150283D01*
X72667Y149950D01*
X72750Y149617D01*
X72958Y149367D01*
X73333Y149242D01*
X74333D01*
G01X71333Y148200D02*
Y150700D01*
X70292D01*
X69958Y150575D01*
X69750Y150408D01*
X69667Y150075D01*
X69750Y149742D01*
X70000Y149533D01*
X70292Y149408D01*
X71333D01*
G01X70292D02*
X69667Y148200D01*
G01X68417Y148575D02*
X68167Y148367D01*
X67875Y148242D01*
X67500Y148200D01*
X67125Y148283D01*
X66833Y148450D01*
X66625Y148742D01*
X66583Y149075D01*
X66667Y149408D01*
X66875Y149617D01*
X67167Y149783D01*
X67458Y149825D01*
X67750Y149783D01*
X68125Y149617D01*
X68000Y150700D01*
X66875D01*
G01X65417Y148575D02*
X65167Y148367D01*
X64875Y148242D01*
X64500Y148200D01*
X64125Y148283D01*
X63833Y148450D01*
X63625Y148742D01*
X63583Y149075D01*
X63667Y149408D01*
X63875Y149617D01*
X64167Y149783D01*
X64458Y149825D01*
X64750Y149783D01*
X65125Y149617D01*
X65000Y150700D01*
X63875D01*
G01X81933Y205200D02*
Y207700D01*
X80892D01*
X80558Y207575D01*
X80350Y207408D01*
X80267Y207075D01*
X80350Y206742D01*
X80600Y206533D01*
X80892Y206408D01*
X81933D01*
G01X80892D02*
X80267Y205200D01*
G01X78100D02*
Y207700D01*
X78600Y207200D01*
G01Y205200D02*
X77600D01*
G01X75100Y207700D02*
X75433Y207617D01*
X75683Y207408D01*
X75850Y207158D01*
X75975Y206825D01*
X76017Y206450D01*
X75975Y206075D01*
X75850Y205742D01*
X75683Y205492D01*
X75433Y205283D01*
X75100Y205200D01*
X74767Y205283D01*
X74517Y205492D01*
X74350Y205742D01*
X74225Y206075D01*
X74183Y206450D01*
X74225Y206825D01*
X74350Y207158D01*
X74517Y207408D01*
X74767Y207617D01*
X75100Y207700D01*
G01X72892Y207283D02*
X72642Y207533D01*
X72350Y207658D01*
X72017Y207700D01*
X71600Y207617D01*
X71308Y207408D01*
X71225Y207158D01*
X71267Y206908D01*
X71433Y206700D01*
X72267Y206283D01*
X72642Y205992D01*
X72892Y205575D01*
X72975Y205200D01*
X71225D01*
G01X40733Y175500D02*
Y178000D01*
X39692D01*
X39358Y177875D01*
X39150Y177708D01*
X39067Y177375D01*
X39150Y177042D01*
X39400Y176833D01*
X39692Y176708D01*
X40733D01*
G01X39692D02*
X39067Y175500D01*
G01X37817Y176000D02*
X37567Y175708D01*
X37233Y175542D01*
X36858Y175500D01*
X36525Y175542D01*
X36192Y175750D01*
X35983Y176000D01*
X35942Y176250D01*
X36025Y176542D01*
X36317Y176750D01*
X36608Y176833D01*
X36983D01*
G01X36608D02*
X36358Y176958D01*
X36150Y177167D01*
X36067Y177417D01*
X36150Y177667D01*
X36358Y177875D01*
X36733Y178000D01*
X37108Y177958D01*
X37483Y177792D01*
G01X34817Y176000D02*
X34567Y175708D01*
X34233Y175542D01*
X33858Y175500D01*
X33525Y175542D01*
X33192Y175750D01*
X32983Y176000D01*
X32942Y176250D01*
X33025Y176542D01*
X33317Y176750D01*
X33608Y176833D01*
X33983D01*
G01X33608D02*
X33358Y176958D01*
X33150Y177167D01*
X33067Y177417D01*
X33150Y177667D01*
X33358Y177875D01*
X33733Y178000D01*
X34108Y177958D01*
X34483Y177792D01*
G01X30900Y175500D02*
X30608Y175542D01*
X30275Y175667D01*
X30067Y175875D01*
X29983Y176167D01*
X30067Y176458D01*
X30317Y176708D01*
X30692Y176833D01*
X31108D01*
X31358Y176917D01*
X31567Y177125D01*
X31650Y177417D01*
X31525Y177708D01*
X31233Y177917D01*
X30900Y178000D01*
X30567Y177917D01*
X30275Y177708D01*
X30150Y177417D01*
X30233Y177125D01*
X30442Y176917D01*
X30692Y176833D01*
X31108D01*
X31483Y176708D01*
X31733Y176458D01*
X31817Y176167D01*
X31733Y175875D01*
X31525Y175667D01*
X31192Y175542D01*
X30900Y175500D01*
G01X83233Y194800D02*
Y197300D01*
X82192D01*
X81858Y197175D01*
X81650Y197008D01*
X81567Y196675D01*
X81650Y196342D01*
X81900Y196133D01*
X82192Y196008D01*
X83233D01*
G01X82192D02*
X81567Y194800D01*
G01X80317Y195300D02*
X80067Y195008D01*
X79733Y194842D01*
X79358Y194800D01*
X79025Y194842D01*
X78692Y195050D01*
X78483Y195300D01*
X78442Y195550D01*
X78525Y195842D01*
X78817Y196050D01*
X79108Y196133D01*
X79483D01*
G01X79108D02*
X78858Y196258D01*
X78650Y196467D01*
X78567Y196717D01*
X78650Y196967D01*
X78858Y197175D01*
X79233Y197300D01*
X79608Y197258D01*
X79983Y197092D01*
G01X77317Y195300D02*
X77067Y195008D01*
X76733Y194842D01*
X76358Y194800D01*
X76025Y194842D01*
X75692Y195050D01*
X75483Y195300D01*
X75442Y195550D01*
X75525Y195842D01*
X75817Y196050D01*
X76108Y196133D01*
X76483D01*
G01X76108D02*
X75858Y196258D01*
X75650Y196467D01*
X75567Y196717D01*
X75650Y196967D01*
X75858Y197175D01*
X76233Y197300D01*
X76608Y197258D01*
X76983Y197092D01*
G01X73483Y194800D02*
X73400Y195342D01*
X73275Y195800D01*
X73108Y196217D01*
X72900Y196675D01*
X72567Y197300D01*
X74233D01*
G01X37033Y194800D02*
Y197300D01*
X35992D01*
X35658Y197175D01*
X35450Y197008D01*
X35367Y196675D01*
X35450Y196342D01*
X35700Y196133D01*
X35992Y196008D01*
X37033D01*
G01X35992D02*
X35367Y194800D01*
G01X34117Y195300D02*
X33867Y195008D01*
X33533Y194842D01*
X33158Y194800D01*
X32825Y194842D01*
X32492Y195050D01*
X32283Y195300D01*
X32242Y195550D01*
X32325Y195842D01*
X32617Y196050D01*
X32908Y196133D01*
X33283D01*
G01X32908D02*
X32658Y196258D01*
X32450Y196467D01*
X32367Y196717D01*
X32450Y196967D01*
X32658Y197175D01*
X33033Y197300D01*
X33408Y197258D01*
X33783Y197092D01*
G01X31117Y195300D02*
X30867Y195008D01*
X30533Y194842D01*
X30158Y194800D01*
X29825Y194842D01*
X29492Y195050D01*
X29283Y195300D01*
X29242Y195550D01*
X29325Y195842D01*
X29617Y196050D01*
X29908Y196133D01*
X30283D01*
G01X29908D02*
X29658Y196258D01*
X29450Y196467D01*
X29367Y196717D01*
X29450Y196967D01*
X29658Y197175D01*
X30033Y197300D01*
X30408Y197258D01*
X30783Y197092D01*
G01X27992Y195842D02*
X27700Y196133D01*
X27450Y196300D01*
X27117Y196383D01*
X26825Y196300D01*
X26617Y196133D01*
X26450Y195883D01*
X26408Y195592D01*
X26450Y195342D01*
X26617Y195092D01*
X26867Y194883D01*
X27158Y194800D01*
X27492Y194883D01*
X27783Y195133D01*
X27950Y195508D01*
X27992Y195925D01*
X27908Y196467D01*
X27783Y196758D01*
X27575Y197050D01*
X27283Y197258D01*
X26992Y197300D01*
X26700Y197217D01*
X26492Y197008D01*
G01X82833Y200700D02*
Y203200D01*
X81792D01*
X81458Y203075D01*
X81250Y202908D01*
X81167Y202575D01*
X81250Y202242D01*
X81500Y202033D01*
X81792Y201908D01*
X82833D01*
G01X81792D02*
X81167Y200700D01*
G01X79917Y201200D02*
X79667Y200908D01*
X79333Y200742D01*
X78958Y200700D01*
X78625Y200742D01*
X78292Y200950D01*
X78083Y201200D01*
X78042Y201450D01*
X78125Y201742D01*
X78417Y201950D01*
X78708Y202033D01*
X79083D01*
G01X78708D02*
X78458Y202158D01*
X78250Y202367D01*
X78167Y202617D01*
X78250Y202867D01*
X78458Y203075D01*
X78833Y203200D01*
X79208Y203158D01*
X79583Y202992D01*
G01X76917Y201200D02*
X76667Y200908D01*
X76333Y200742D01*
X75958Y200700D01*
X75625Y200742D01*
X75292Y200950D01*
X75083Y201200D01*
X75042Y201450D01*
X75125Y201742D01*
X75417Y201950D01*
X75708Y202033D01*
X76083D01*
G01X75708D02*
X75458Y202158D01*
X75250Y202367D01*
X75167Y202617D01*
X75250Y202867D01*
X75458Y203075D01*
X75833Y203200D01*
X76208Y203158D01*
X76583Y202992D01*
G01X73917Y201200D02*
X73667Y200908D01*
X73333Y200742D01*
X72958Y200700D01*
X72625Y200742D01*
X72292Y200950D01*
X72083Y201200D01*
X72042Y201450D01*
X72125Y201742D01*
X72417Y201950D01*
X72708Y202033D01*
X73083D01*
G01X72708D02*
X72458Y202158D01*
X72250Y202367D01*
X72167Y202617D01*
X72250Y202867D01*
X72458Y203075D01*
X72833Y203200D01*
X73208Y203158D01*
X73583Y202992D01*
G01X46100Y165367D02*
X48600D01*
Y166408D01*
X48475Y166742D01*
X48308Y166950D01*
X47975Y167033D01*
X47642Y166950D01*
X47433Y166700D01*
X47308Y166408D01*
Y165367D01*
G01Y166408D02*
X46100Y167033D01*
G01X48183Y168408D02*
X48433Y168658D01*
X48558Y168950D01*
X48600Y169283D01*
X48517Y169700D01*
X48308Y169992D01*
X48058Y170075D01*
X47808Y170033D01*
X47600Y169867D01*
X47183Y169033D01*
X46892Y168658D01*
X46475Y168408D01*
X46100Y168325D01*
Y170075D01*
G01X46475Y171283D02*
X46267Y171533D01*
X46142Y171825D01*
X46100Y172200D01*
X46183Y172575D01*
X46350Y172867D01*
X46642Y173075D01*
X46975Y173117D01*
X47308Y173033D01*
X47517Y172825D01*
X47683Y172533D01*
X47725Y172242D01*
X47683Y171950D01*
X47517Y171575D01*
X48600Y171700D01*
Y172825D01*
G01X46100Y175200D02*
X46142Y175492D01*
X46267Y175825D01*
X46475Y176033D01*
X46767Y176117D01*
X47058Y176033D01*
X47308Y175783D01*
X47433Y175408D01*
Y174992D01*
X47517Y174742D01*
X47725Y174533D01*
X48017Y174450D01*
X48308Y174575D01*
X48517Y174867D01*
X48600Y175200D01*
X48517Y175533D01*
X48308Y175825D01*
X48017Y175950D01*
X47725Y175867D01*
X47517Y175658D01*
X47433Y175408D01*
Y174992D01*
X47308Y174617D01*
X47058Y174367D01*
X46767Y174283D01*
X46475Y174367D01*
X46267Y174575D01*
X46142Y174908D01*
X46100Y175200D01*
G01X59900Y173500D02*
X60233Y173542D01*
X60525Y173708D01*
X60775Y173958D01*
X60942Y174250D01*
X61025Y174583D01*
Y174917D01*
X60942Y175250D01*
X60775Y175542D01*
X60525Y175792D01*
X60233Y175958D01*
X59900Y176000D01*
X59567Y175958D01*
X59275Y175792D01*
X59025Y175542D01*
X58858Y175250D01*
X58775Y174917D01*
Y174583D01*
X58858Y174250D01*
X59025Y173958D01*
X59275Y173708D01*
X59567Y173542D01*
X59900Y173500D01*
G01X59567Y174167D02*
X59067Y173500D01*
G01X56900D02*
X56608Y173542D01*
X56275Y173667D01*
X56067Y173875D01*
X55983Y174167D01*
X56067Y174458D01*
X56317Y174708D01*
X56692Y174833D01*
X57108D01*
X57358Y174917D01*
X57567Y175125D01*
X57650Y175417D01*
X57525Y175708D01*
X57233Y175917D01*
X56900Y176000D01*
X56567Y175917D01*
X56275Y175708D01*
X56150Y175417D01*
X56233Y175125D01*
X56442Y174917D01*
X56692Y174833D01*
X57108D01*
X57483Y174708D01*
X57733Y174458D01*
X57817Y174167D01*
X57733Y173875D01*
X57525Y173667D01*
X57192Y173542D01*
X56900Y173500D01*
G01X43433Y211400D02*
Y213900D01*
X42392D01*
X42058Y213775D01*
X41850Y213608D01*
X41767Y213275D01*
X41850Y212942D01*
X42100Y212733D01*
X42392Y212608D01*
X43433D01*
G01X42392D02*
X41767Y211400D01*
G01X40392Y213483D02*
X40142Y213733D01*
X39850Y213858D01*
X39517Y213900D01*
X39100Y213817D01*
X38808Y213608D01*
X38725Y213358D01*
X38767Y213108D01*
X38933Y212900D01*
X39767Y212483D01*
X40142Y212192D01*
X40392Y211775D01*
X40475Y211400D01*
X38725D01*
G01X36600D02*
Y213900D01*
X37100Y213400D01*
G01Y211400D02*
X36100D01*
G01X33600D02*
X33308Y211442D01*
X32975Y211567D01*
X32767Y211775D01*
X32683Y212067D01*
X32767Y212358D01*
X33017Y212608D01*
X33392Y212733D01*
X33808D01*
X34058Y212817D01*
X34267Y213025D01*
X34350Y213317D01*
X34225Y213608D01*
X33933Y213817D01*
X33600Y213900D01*
X33267Y213817D01*
X32975Y213608D01*
X32850Y213317D01*
X32933Y213025D01*
X33142Y212817D01*
X33392Y212733D01*
X33808D01*
X34183Y212608D01*
X34433Y212358D01*
X34517Y212067D01*
X34433Y211775D01*
X34225Y211567D01*
X33892Y211442D01*
X33600Y211400D01*
G01X60010Y260022D02*
X60135Y259772D01*
X60218Y259480D01*
Y259147D01*
X60093Y258772D01*
X59885Y258480D01*
X59635Y258272D01*
X59218Y258105D01*
X58843Y258063D01*
X58468Y258147D01*
X58218Y258272D01*
X57968Y258522D01*
X57801Y258813D01*
X57718Y259105D01*
Y259397D01*
X57801Y259688D01*
X57926Y259938D01*
X58093Y260147D01*
G01X57718Y262105D02*
X60218D01*
X59718Y261605D01*
G01X57718D02*
Y262605D01*
G01Y265022D02*
X58260Y265105D01*
X58718Y265230D01*
X59135Y265397D01*
X59593Y265605D01*
X60218Y265938D01*
Y264272D01*
G01X57718Y268105D02*
X60218D01*
X59718Y267605D01*
G01X57718D02*
Y268605D01*
G01X29312Y257197D02*
X31812D01*
Y258238D01*
X31687Y258572D01*
X31520Y258780D01*
X31187Y258863D01*
X30854Y258780D01*
X30645Y258530D01*
X30520Y258238D01*
Y257197D01*
G01Y258238D02*
X29312Y258863D01*
G01Y261030D02*
X31812D01*
X31312Y260530D01*
G01X29312D02*
Y261530D01*
G01X29687Y263113D02*
X29479Y263363D01*
X29354Y263655D01*
X29312Y264030D01*
X29395Y264405D01*
X29562Y264697D01*
X29854Y264905D01*
X30187Y264947D01*
X30520Y264863D01*
X30729Y264655D01*
X30895Y264363D01*
X30937Y264072D01*
X30895Y263780D01*
X30729Y263405D01*
X31812Y263530D01*
Y264655D01*
G01X29312Y267030D02*
X31812D01*
X31312Y266530D01*
G01X29312D02*
Y267530D01*
G01X34872Y256953D02*
X37372D01*
Y257994D01*
X37247Y258328D01*
X37080Y258536D01*
X36747Y258619D01*
X36414Y258536D01*
X36205Y258286D01*
X36080Y257994D01*
Y256953D01*
G01Y257994D02*
X34872Y258619D01*
G01Y260786D02*
X37372D01*
X36872Y260286D01*
G01X34872D02*
Y261286D01*
G01X35247Y262869D02*
X35039Y263119D01*
X34914Y263411D01*
X34872Y263786D01*
X34955Y264161D01*
X35122Y264453D01*
X35414Y264661D01*
X35747Y264703D01*
X36080Y264619D01*
X36289Y264411D01*
X36455Y264119D01*
X36497Y263828D01*
X36455Y263536D01*
X36289Y263161D01*
X37372Y263286D01*
Y264411D01*
G01Y266786D02*
X37289Y266453D01*
X37080Y266203D01*
X36830Y266036D01*
X36497Y265911D01*
X36122Y265869D01*
X35747Y265911D01*
X35414Y266036D01*
X35164Y266203D01*
X34955Y266453D01*
X34872Y266786D01*
X34955Y267119D01*
X35164Y267369D01*
X35414Y267536D01*
X35747Y267661D01*
X36122Y267703D01*
X36497Y267661D01*
X36830Y267536D01*
X37080Y267369D01*
X37289Y267119D01*
X37372Y266786D01*
G01X56133Y250500D02*
Y253000D01*
X55092D01*
X54758Y252875D01*
X54550Y252708D01*
X54467Y252375D01*
X54550Y252042D01*
X54800Y251833D01*
X55092Y251708D01*
X56133D01*
G01X55092D02*
X54467Y250500D01*
G01X53092Y251542D02*
X52800Y251833D01*
X52550Y252000D01*
X52217Y252083D01*
X51925Y252000D01*
X51717Y251833D01*
X51550Y251583D01*
X51508Y251292D01*
X51550Y251042D01*
X51717Y250792D01*
X51967Y250583D01*
X52258Y250500D01*
X52592Y250583D01*
X52883Y250833D01*
X53050Y251208D01*
X53092Y251625D01*
X53008Y252167D01*
X52883Y252458D01*
X52675Y252750D01*
X52383Y252958D01*
X52092Y253000D01*
X51800Y252917D01*
X51592Y252708D01*
G01X50008Y250792D02*
X49717Y250583D01*
X49383Y250500D01*
X49050Y250583D01*
X48758Y250833D01*
X48550Y251208D01*
X48467Y251583D01*
Y252042D01*
X48550Y252417D01*
X48758Y252750D01*
X49008Y252917D01*
X49300Y253000D01*
X49633Y252917D01*
X49883Y252750D01*
X50050Y252500D01*
X50133Y252167D01*
X50050Y251875D01*
X49842Y251583D01*
X49592Y251417D01*
X49300Y251375D01*
X48967Y251458D01*
X48717Y251667D01*
X48467Y252042D01*
G01X80933Y210200D02*
Y212700D01*
X79892D01*
X79558Y212575D01*
X79350Y212408D01*
X79267Y212075D01*
X79350Y211742D01*
X79600Y211533D01*
X79892Y211408D01*
X80933D01*
G01X79892D02*
X79267Y210200D01*
G01X77100D02*
Y212700D01*
X77600Y212200D01*
G01Y210200D02*
X76600D01*
G01X74100Y212700D02*
X74433Y212617D01*
X74683Y212408D01*
X74850Y212158D01*
X74975Y211825D01*
X75017Y211450D01*
X74975Y211075D01*
X74850Y210742D01*
X74683Y210492D01*
X74433Y210283D01*
X74100Y210200D01*
X73767Y210283D01*
X73517Y210492D01*
X73350Y210742D01*
X73225Y211075D01*
X73183Y211450D01*
X73225Y211825D01*
X73350Y212158D01*
X73517Y212408D01*
X73767Y212617D01*
X74100Y212700D01*
G01X71100D02*
X71433Y212617D01*
X71683Y212408D01*
X71850Y212158D01*
X71975Y211825D01*
X72017Y211450D01*
X71975Y211075D01*
X71850Y210742D01*
X71683Y210492D01*
X71433Y210283D01*
X71100Y210200D01*
X70767Y210283D01*
X70517Y210492D01*
X70350Y210742D01*
X70225Y211075D01*
X70183Y211450D01*
X70225Y211825D01*
X70350Y212158D01*
X70517Y212408D01*
X70767Y212617D01*
X71100Y212700D01*
G01X22300Y276000D02*
Y273500D01*
G01X23258Y276000D02*
X21342D01*
G01X20133Y273500D02*
Y276000D01*
X19133D01*
X18800Y275875D01*
X18550Y275583D01*
X18467Y275250D01*
X18550Y274917D01*
X18758Y274667D01*
X19133Y274542D01*
X20133D01*
G01X16300Y273500D02*
Y276000D01*
X16800Y275500D01*
G01Y273500D02*
X15800D01*
G01X14092Y274542D02*
X13800Y274833D01*
X13550Y275000D01*
X13217Y275083D01*
X12925Y275000D01*
X12717Y274833D01*
X12550Y274583D01*
X12508Y274292D01*
X12550Y274042D01*
X12717Y273792D01*
X12967Y273583D01*
X13258Y273500D01*
X13592Y273583D01*
X13883Y273833D01*
X14050Y274208D01*
X14092Y274625D01*
X14008Y275167D01*
X13883Y275458D01*
X13675Y275750D01*
X13383Y275958D01*
X13092Y276000D01*
X12800Y275917D01*
X12592Y275708D01*
G01X11217Y273875D02*
X10967Y273667D01*
X10675Y273542D01*
X10300Y273500D01*
X9925Y273583D01*
X9633Y273750D01*
X9425Y274042D01*
X9383Y274375D01*
X9467Y274708D01*
X9675Y274917D01*
X9967Y275083D01*
X10258Y275125D01*
X10550Y275083D01*
X10925Y274917D01*
X10800Y276000D01*
X9675D01*
G01X42100Y205800D02*
X42433Y205842D01*
X42725Y206008D01*
X42975Y206258D01*
X43142Y206550D01*
X43225Y206883D01*
Y207217D01*
X43142Y207550D01*
X42975Y207842D01*
X42725Y208092D01*
X42433Y208258D01*
X42100Y208300D01*
X41767Y208258D01*
X41475Y208092D01*
X41225Y207842D01*
X41058Y207550D01*
X40975Y207217D01*
Y206883D01*
X41058Y206550D01*
X41225Y206258D01*
X41475Y206008D01*
X41767Y205842D01*
X42100Y205800D01*
G01X41767Y206467D02*
X41267Y205800D01*
G01X39892Y206842D02*
X39600Y207133D01*
X39350Y207300D01*
X39017Y207383D01*
X38725Y207300D01*
X38517Y207133D01*
X38350Y206883D01*
X38308Y206592D01*
X38350Y206342D01*
X38517Y206092D01*
X38767Y205883D01*
X39058Y205800D01*
X39392Y205883D01*
X39683Y206133D01*
X39850Y206508D01*
X39892Y206925D01*
X39808Y207467D01*
X39683Y207758D01*
X39475Y208050D01*
X39183Y208258D01*
X38892Y208300D01*
X38600Y208217D01*
X38392Y208008D01*
G01X20217Y291300D02*
Y289508D01*
X20050Y289133D01*
X19717Y288883D01*
X19300Y288800D01*
X18883Y288883D01*
X18550Y289133D01*
X18383Y289508D01*
Y291300D01*
G01X17092Y289842D02*
X16800Y290133D01*
X16550Y290300D01*
X16217Y290383D01*
X15925Y290300D01*
X15717Y290133D01*
X15550Y289883D01*
X15508Y289592D01*
X15550Y289342D01*
X15717Y289092D01*
X15967Y288883D01*
X16258Y288800D01*
X16592Y288883D01*
X16883Y289133D01*
X17050Y289508D01*
X17092Y289925D01*
X17008Y290467D01*
X16883Y290758D01*
X16675Y291050D01*
X16383Y291258D01*
X16092Y291300D01*
X15800Y291217D01*
X15592Y291008D01*
G01X37192Y316117D02*
X37317Y315867D01*
X37400Y315575D01*
Y315242D01*
X37275Y314867D01*
X37067Y314575D01*
X36817Y314367D01*
X36400Y314200D01*
X36025Y314158D01*
X35650Y314242D01*
X35400Y314367D01*
X35150Y314617D01*
X34983Y314908D01*
X34900Y315200D01*
Y315492D01*
X34983Y315783D01*
X35108Y316033D01*
X35275Y316242D01*
G01X36983Y317408D02*
X37233Y317658D01*
X37358Y317950D01*
X37400Y318283D01*
X37317Y318700D01*
X37108Y318992D01*
X36858Y319075D01*
X36608Y319033D01*
X36400Y318867D01*
X35983Y318033D01*
X35692Y317658D01*
X35275Y317408D01*
X34900Y317325D01*
Y319075D01*
G01X36983Y320408D02*
X37233Y320658D01*
X37358Y320950D01*
X37400Y321283D01*
X37317Y321700D01*
X37108Y321992D01*
X36858Y322075D01*
X36608Y322033D01*
X36400Y321867D01*
X35983Y321033D01*
X35692Y320658D01*
X35275Y320408D01*
X34900Y320325D01*
Y322075D01*
G01X35400Y323283D02*
X35108Y323533D01*
X34942Y323867D01*
X34900Y324242D01*
X34942Y324575D01*
X35150Y324908D01*
X35400Y325117D01*
X35650Y325158D01*
X35942Y325075D01*
X36150Y324783D01*
X36233Y324492D01*
Y324117D01*
G01Y324492D02*
X36358Y324742D01*
X36567Y324950D01*
X36817Y325033D01*
X37067Y324950D01*
X37275Y324742D01*
X37400Y324367D01*
X37358Y323992D01*
X37192Y323617D01*
G01X52083Y293392D02*
X52333Y293517D01*
X52625Y293600D01*
X52958D01*
X53333Y293475D01*
X53625Y293267D01*
X53833Y293017D01*
X54000Y292600D01*
X54042Y292225D01*
X53958Y291850D01*
X53833Y291600D01*
X53583Y291350D01*
X53292Y291183D01*
X53000Y291100D01*
X52708D01*
X52417Y291183D01*
X52167Y291308D01*
X51958Y291475D01*
G01X50792Y293183D02*
X50542Y293433D01*
X50250Y293558D01*
X49917Y293600D01*
X49500Y293517D01*
X49208Y293308D01*
X49125Y293058D01*
X49167Y292808D01*
X49333Y292600D01*
X50167Y292183D01*
X50542Y291892D01*
X50792Y291475D01*
X50875Y291100D01*
X49125D01*
G01X47792Y293183D02*
X47542Y293433D01*
X47250Y293558D01*
X46917Y293600D01*
X46500Y293517D01*
X46208Y293308D01*
X46125Y293058D01*
X46167Y292808D01*
X46333Y292600D01*
X47167Y292183D01*
X47542Y291892D01*
X47792Y291475D01*
X47875Y291100D01*
X46125D01*
G01X44792Y293183D02*
X44542Y293433D01*
X44250Y293558D01*
X43917Y293600D01*
X43500Y293517D01*
X43208Y293308D01*
X43125Y293058D01*
X43167Y292808D01*
X43333Y292600D01*
X44167Y292183D01*
X44542Y291892D01*
X44792Y291475D01*
X44875Y291100D01*
X43125D01*
G01X21500Y317567D02*
X24000D01*
Y318608D01*
X23875Y318942D01*
X23708Y319150D01*
X23375Y319233D01*
X23042Y319150D01*
X22833Y318900D01*
X22708Y318608D01*
Y317567D01*
G01Y318608D02*
X21500Y319233D01*
G01X23583Y320608D02*
X23833Y320858D01*
X23958Y321150D01*
X24000Y321483D01*
X23917Y321900D01*
X23708Y322192D01*
X23458Y322275D01*
X23208Y322233D01*
X23000Y322067D01*
X22583Y321233D01*
X22292Y320858D01*
X21875Y320608D01*
X21500Y320525D01*
Y322275D01*
G01Y324900D02*
X24000D01*
X22208Y323358D01*
Y325442D01*
G01X23583Y326608D02*
X23833Y326858D01*
X23958Y327150D01*
X24000Y327483D01*
X23917Y327900D01*
X23708Y328192D01*
X23458Y328275D01*
X23208Y328233D01*
X23000Y328067D01*
X22583Y327233D01*
X22292Y326858D01*
X21875Y326608D01*
X21500Y326525D01*
Y328275D01*
G01X55133Y278600D02*
Y281100D01*
X54092D01*
X53758Y280975D01*
X53550Y280808D01*
X53467Y280475D01*
X53550Y280142D01*
X53800Y279933D01*
X54092Y279808D01*
X55133D01*
G01X54092D02*
X53467Y278600D01*
G01X51300D02*
Y281100D01*
X51800Y280600D01*
G01Y278600D02*
X50800D01*
G01X47800D02*
Y281100D01*
X49342Y279308D01*
X47258D01*
G01X45383Y278600D02*
X45300Y279142D01*
X45175Y279600D01*
X45008Y280017D01*
X44800Y280475D01*
X44467Y281100D01*
X46133D01*
G01X25705Y317441D02*
X28205D01*
Y318482D01*
X28080Y318816D01*
X27913Y319024D01*
X27580Y319107D01*
X27247Y319024D01*
X27038Y318774D01*
X26913Y318482D01*
Y317441D01*
G01Y318482D02*
X25705Y319107D01*
G01Y321274D02*
X28205D01*
X27705Y320774D01*
G01X25705D02*
Y321774D01*
G01Y324774D02*
X28205D01*
X26413Y323232D01*
Y325316D01*
G01X25997Y326566D02*
X25788Y326857D01*
X25705Y327191D01*
X25788Y327524D01*
X26038Y327816D01*
X26413Y328024D01*
X26788Y328107D01*
X27247D01*
X27622Y328024D01*
X27955Y327816D01*
X28122Y327566D01*
X28205Y327274D01*
X28122Y326941D01*
X27955Y326691D01*
X27705Y326524D01*
X27372Y326441D01*
X27080Y326524D01*
X26788Y326732D01*
X26622Y326982D01*
X26580Y327274D01*
X26663Y327607D01*
X26872Y327857D01*
X27247Y328107D01*
G01X30187Y317532D02*
X32687D01*
Y318573D01*
X32562Y318907D01*
X32395Y319115D01*
X32062Y319198D01*
X31729Y319115D01*
X31520Y318865D01*
X31395Y318573D01*
Y317532D01*
G01Y318573D02*
X30187Y319198D01*
G01Y321365D02*
X32687D01*
X32187Y320865D01*
G01X30187D02*
Y321865D01*
G01Y324865D02*
X32687D01*
X30895Y323323D01*
Y325407D01*
G01X30187Y327365D02*
X30229Y327657D01*
X30354Y327990D01*
X30562Y328198D01*
X30854Y328282D01*
X31145Y328198D01*
X31395Y327948D01*
X31520Y327573D01*
Y327157D01*
X31604Y326907D01*
X31812Y326698D01*
X32104Y326615D01*
X32395Y326740D01*
X32604Y327032D01*
X32687Y327365D01*
X32604Y327698D01*
X32395Y327990D01*
X32104Y328115D01*
X31812Y328032D01*
X31604Y327823D01*
X31520Y327573D01*
Y327157D01*
X31395Y326782D01*
X31145Y326532D01*
X30854Y326448D01*
X30562Y326532D01*
X30354Y326740D01*
X30229Y327073D01*
X30187Y327365D01*
G01X70992Y306417D02*
X71117Y306167D01*
X71200Y305875D01*
Y305542D01*
X71075Y305167D01*
X70867Y304875D01*
X70617Y304667D01*
X70200Y304500D01*
X69825Y304458D01*
X69450Y304542D01*
X69200Y304667D01*
X68950Y304917D01*
X68783Y305208D01*
X68700Y305500D01*
Y305792D01*
X68783Y306083D01*
X68908Y306333D01*
X69075Y306542D01*
G01X68700Y308500D02*
X71200D01*
X70700Y308000D01*
G01X68700D02*
Y309000D01*
G01X69742Y310708D02*
X70033Y311000D01*
X70200Y311250D01*
X70283Y311583D01*
X70200Y311875D01*
X70033Y312083D01*
X69783Y312250D01*
X69492Y312292D01*
X69242Y312250D01*
X68992Y312083D01*
X68783Y311833D01*
X68700Y311542D01*
X68783Y311208D01*
X69033Y310917D01*
X69408Y310750D01*
X69825Y310708D01*
X70367Y310792D01*
X70658Y310917D01*
X70950Y311125D01*
X71158Y311417D01*
X71200Y311708D01*
X71117Y312000D01*
X70908Y312208D01*
G01X69075Y313583D02*
X68867Y313833D01*
X68742Y314125D01*
X68700Y314500D01*
X68783Y314875D01*
X68950Y315167D01*
X69242Y315375D01*
X69575Y315417D01*
X69908Y315333D01*
X70117Y315125D01*
X70283Y314833D01*
X70325Y314542D01*
X70283Y314250D01*
X70117Y313875D01*
X71200Y314000D01*
Y315125D01*
G01X51405Y394173D02*
X51655Y394298D01*
X51947Y394381D01*
X52280D01*
X52655Y394256D01*
X52947Y394048D01*
X53155Y393798D01*
X53322Y393381D01*
X53364Y393006D01*
X53280Y392631D01*
X53155Y392381D01*
X52905Y392131D01*
X52614Y391964D01*
X52322Y391881D01*
X52030D01*
X51739Y391964D01*
X51489Y392089D01*
X51280Y392256D01*
G01X49322Y391881D02*
Y394381D01*
X49822Y393881D01*
G01Y391881D02*
X48822D01*
G01X47114Y393964D02*
X46864Y394214D01*
X46572Y394339D01*
X46239Y394381D01*
X45822Y394298D01*
X45530Y394089D01*
X45447Y393839D01*
X45489Y393589D01*
X45655Y393381D01*
X46489Y392964D01*
X46864Y392673D01*
X47114Y392256D01*
X47197Y391881D01*
X45447D01*
G01X43322Y394381D02*
X43655Y394298D01*
X43905Y394089D01*
X44072Y393839D01*
X44197Y393506D01*
X44239Y393131D01*
X44197Y392756D01*
X44072Y392423D01*
X43905Y392173D01*
X43655Y391964D01*
X43322Y391881D01*
X42989Y391964D01*
X42739Y392173D01*
X42572Y392423D01*
X42447Y392756D01*
X42405Y393131D01*
X42447Y393506D01*
X42572Y393839D01*
X42739Y394089D01*
X42989Y394298D01*
X43322Y394381D01*
G01X50955Y390520D02*
X51205Y390645D01*
X51497Y390728D01*
X51830D01*
X52205Y390603D01*
X52497Y390395D01*
X52705Y390145D01*
X52872Y389728D01*
X52914Y389353D01*
X52830Y388978D01*
X52705Y388728D01*
X52455Y388478D01*
X52164Y388311D01*
X51872Y388228D01*
X51580D01*
X51289Y388311D01*
X51039Y388436D01*
X50830Y388603D01*
G01X48872Y388228D02*
Y390728D01*
X49372Y390228D01*
G01Y388228D02*
X48372D01*
G01X46664Y390311D02*
X46414Y390561D01*
X46122Y390686D01*
X45789Y390728D01*
X45372Y390645D01*
X45080Y390436D01*
X44997Y390186D01*
X45039Y389936D01*
X45205Y389728D01*
X46039Y389311D01*
X46414Y389020D01*
X46664Y388603D01*
X46747Y388228D01*
X44997D01*
G01X43789Y388728D02*
X43539Y388436D01*
X43205Y388270D01*
X42830Y388228D01*
X42497Y388270D01*
X42164Y388478D01*
X41955Y388728D01*
X41914Y388978D01*
X41997Y389270D01*
X42289Y389478D01*
X42580Y389561D01*
X42955D01*
G01X42580D02*
X42330Y389686D01*
X42122Y389895D01*
X42039Y390145D01*
X42122Y390395D01*
X42330Y390603D01*
X42705Y390728D01*
X43080Y390686D01*
X43455Y390520D01*
G01X80241Y406276D02*
Y408776D01*
X79200D01*
X78866Y408651D01*
X78658Y408484D01*
X78575Y408151D01*
X78658Y407818D01*
X78908Y407609D01*
X79200Y407484D01*
X80241D01*
G01X79200D02*
X78575Y406276D01*
G01X77325Y406776D02*
X77075Y406484D01*
X76741Y406318D01*
X76366Y406276D01*
X76033Y406318D01*
X75700Y406526D01*
X75491Y406776D01*
X75450Y407026D01*
X75533Y407318D01*
X75825Y407526D01*
X76116Y407609D01*
X76491D01*
G01X76116D02*
X75866Y407734D01*
X75658Y407943D01*
X75575Y408193D01*
X75658Y408443D01*
X75866Y408651D01*
X76241Y408776D01*
X76616Y408734D01*
X76991Y408568D01*
G01X73408Y406276D02*
Y408776D01*
X73908Y408276D01*
G01Y406276D02*
X72908D01*
G01X53847Y383763D02*
Y386263D01*
X52806D01*
X52472Y386138D01*
X52264Y385971D01*
X52181Y385638D01*
X52264Y385305D01*
X52514Y385096D01*
X52806Y384971D01*
X53847D01*
G01X52806D02*
X52181Y383763D01*
G01X50806Y385846D02*
X50556Y386096D01*
X50264Y386221D01*
X49931Y386263D01*
X49514Y386180D01*
X49222Y385971D01*
X49139Y385721D01*
X49181Y385471D01*
X49347Y385263D01*
X50181Y384846D01*
X50556Y384555D01*
X50806Y384138D01*
X50889Y383763D01*
X49139D01*
G01X47722Y384055D02*
X47431Y383846D01*
X47097Y383763D01*
X46764Y383846D01*
X46472Y384096D01*
X46264Y384471D01*
X46181Y384846D01*
Y385305D01*
X46264Y385680D01*
X46472Y386013D01*
X46722Y386180D01*
X47014Y386263D01*
X47347Y386180D01*
X47597Y386013D01*
X47764Y385763D01*
X47847Y385430D01*
X47764Y385138D01*
X47556Y384846D01*
X47306Y384680D01*
X47014Y384638D01*
X46681Y384721D01*
X46431Y384930D01*
X46181Y385305D01*
G01X53604Y379743D02*
Y382243D01*
X52563D01*
X52229Y382118D01*
X52021Y381951D01*
X51938Y381618D01*
X52021Y381285D01*
X52271Y381076D01*
X52563Y380951D01*
X53604D01*
G01X52563D02*
X51938Y379743D01*
G01X50563Y381826D02*
X50313Y382076D01*
X50021Y382201D01*
X49688Y382243D01*
X49271Y382160D01*
X48979Y381951D01*
X48896Y381701D01*
X48938Y381451D01*
X49104Y381243D01*
X49938Y380826D01*
X50313Y380535D01*
X50563Y380118D01*
X50646Y379743D01*
X48896D01*
G01X46771D02*
Y382243D01*
X47271Y381743D01*
G01Y379743D02*
X46271D01*
G01X80441Y410512D02*
Y413012D01*
X79400D01*
X79066Y412887D01*
X78858Y412720D01*
X78775Y412387D01*
X78858Y412054D01*
X79108Y411845D01*
X79400Y411720D01*
X80441D01*
G01X79400D02*
X78775Y410512D01*
G01X77400Y412595D02*
X77150Y412845D01*
X76858Y412970D01*
X76525Y413012D01*
X76108Y412929D01*
X75816Y412720D01*
X75733Y412470D01*
X75775Y412220D01*
X75941Y412012D01*
X76775Y411595D01*
X77150Y411304D01*
X77400Y410887D01*
X77483Y410512D01*
X75733D01*
G01X73608Y413012D02*
X73941Y412929D01*
X74191Y412720D01*
X74358Y412470D01*
X74483Y412137D01*
X74525Y411762D01*
X74483Y411387D01*
X74358Y411054D01*
X74191Y410804D01*
X73941Y410595D01*
X73608Y410512D01*
X73275Y410595D01*
X73025Y410804D01*
X72858Y411054D01*
X72733Y411387D01*
X72691Y411762D01*
X72733Y412137D01*
X72858Y412470D01*
X73025Y412720D01*
X73275Y412929D01*
X73608Y413012D01*
G01X80458Y414439D02*
Y416939D01*
X79417D01*
X79083Y416814D01*
X78875Y416647D01*
X78792Y416314D01*
X78875Y415981D01*
X79125Y415772D01*
X79417Y415647D01*
X80458D01*
G01X79417D02*
X78792Y414439D01*
G01X76625D02*
Y416939D01*
X77125Y416439D01*
G01Y414439D02*
X76125D01*
G01X74333Y414731D02*
X74042Y414522D01*
X73708Y414439D01*
X73375Y414522D01*
X73083Y414772D01*
X72875Y415147D01*
X72792Y415522D01*
Y415981D01*
X72875Y416356D01*
X73083Y416689D01*
X73333Y416856D01*
X73625Y416939D01*
X73958Y416856D01*
X74208Y416689D01*
X74375Y416439D01*
X74458Y416106D01*
X74375Y415814D01*
X74167Y415522D01*
X73917Y415356D01*
X73625Y415314D01*
X73292Y415397D01*
X73042Y415606D01*
X72792Y415981D01*
G01X68589Y375426D02*
X71089D01*
Y376467D01*
X70964Y376801D01*
X70797Y377009D01*
X70464Y377092D01*
X70131Y377009D01*
X69922Y376759D01*
X69797Y376467D01*
Y375426D01*
G01Y376467D02*
X68589Y377092D01*
G01X69089Y378342D02*
X68797Y378592D01*
X68631Y378926D01*
X68589Y379301D01*
X68631Y379634D01*
X68839Y379967D01*
X69089Y380176D01*
X69339Y380217D01*
X69631Y380134D01*
X69839Y379842D01*
X69922Y379551D01*
Y379176D01*
G01Y379551D02*
X70047Y379801D01*
X70256Y380009D01*
X70506Y380092D01*
X70756Y380009D01*
X70964Y379801D01*
X71089Y379426D01*
X71047Y379051D01*
X70881Y378676D01*
G01X68589Y382259D02*
X68631Y382551D01*
X68756Y382884D01*
X68964Y383092D01*
X69256Y383176D01*
X69547Y383092D01*
X69797Y382842D01*
X69922Y382467D01*
Y382051D01*
X70006Y381801D01*
X70214Y381592D01*
X70506Y381509D01*
X70797Y381634D01*
X71006Y381926D01*
X71089Y382259D01*
X71006Y382592D01*
X70797Y382884D01*
X70506Y383009D01*
X70214Y382926D01*
X70006Y382717D01*
X69922Y382467D01*
Y382051D01*
X69797Y381676D01*
X69547Y381426D01*
X69256Y381342D01*
X68964Y381426D01*
X68756Y381634D01*
X68631Y381967D01*
X68589Y382259D01*
G01X72273Y403398D02*
Y400898D01*
G01X73231Y403398D02*
X71315D01*
G01X70106Y400898D02*
Y403398D01*
X69106D01*
X68773Y403273D01*
X68523Y402981D01*
X68440Y402648D01*
X68523Y402315D01*
X68731Y402065D01*
X69106Y401940D01*
X70106D01*
G01X66981Y401190D02*
X66690Y400981D01*
X66356Y400898D01*
X66023Y400981D01*
X65731Y401231D01*
X65523Y401606D01*
X65440Y401981D01*
Y402440D01*
X65523Y402815D01*
X65731Y403148D01*
X65981Y403315D01*
X66273Y403398D01*
X66606Y403315D01*
X66856Y403148D01*
X67023Y402898D01*
X67106Y402565D01*
X67023Y402273D01*
X66815Y401981D01*
X66565Y401815D01*
X66273Y401773D01*
X65940Y401856D01*
X65690Y402065D01*
X65440Y402440D01*
G01X63273Y400898D02*
Y403398D01*
X63773Y402898D01*
G01Y400898D02*
X62773D01*
G01X52724Y400323D02*
Y397823D01*
G01X53682Y400323D02*
X51766D01*
G01X50557Y397823D02*
Y400323D01*
X49557D01*
X49224Y400198D01*
X48974Y399906D01*
X48891Y399573D01*
X48974Y399240D01*
X49182Y398990D01*
X49557Y398865D01*
X50557D01*
G01X47432Y398115D02*
X47141Y397906D01*
X46807Y397823D01*
X46474Y397906D01*
X46182Y398156D01*
X45974Y398531D01*
X45891Y398906D01*
Y399365D01*
X45974Y399740D01*
X46182Y400073D01*
X46432Y400240D01*
X46724Y400323D01*
X47057Y400240D01*
X47307Y400073D01*
X47474Y399823D01*
X47557Y399490D01*
X47474Y399198D01*
X47266Y398906D01*
X47016Y398740D01*
X46724Y398698D01*
X46391Y398781D01*
X46141Y398990D01*
X45891Y399365D01*
G01X44516Y398865D02*
X44224Y399156D01*
X43974Y399323D01*
X43641Y399406D01*
X43349Y399323D01*
X43141Y399156D01*
X42974Y398906D01*
X42932Y398615D01*
X42974Y398365D01*
X43141Y398115D01*
X43391Y397906D01*
X43682Y397823D01*
X44016Y397906D01*
X44307Y398156D01*
X44474Y398531D01*
X44516Y398948D01*
X44432Y399490D01*
X44307Y399781D01*
X44099Y400073D01*
X43807Y400281D01*
X43516Y400323D01*
X43224Y400240D01*
X43016Y400031D01*
G01X54474Y406762D02*
Y404262D01*
G01X55432Y406762D02*
X53516D01*
G01X52307Y404262D02*
Y406762D01*
X51307D01*
X50974Y406637D01*
X50724Y406345D01*
X50641Y406012D01*
X50724Y405679D01*
X50932Y405429D01*
X51307Y405304D01*
X52307D01*
G01X49182Y404554D02*
X48891Y404345D01*
X48557Y404262D01*
X48224Y404345D01*
X47932Y404595D01*
X47724Y404970D01*
X47641Y405345D01*
Y405804D01*
X47724Y406179D01*
X47932Y406512D01*
X48182Y406679D01*
X48474Y406762D01*
X48807Y406679D01*
X49057Y406512D01*
X49224Y406262D01*
X49307Y405929D01*
X49224Y405637D01*
X49016Y405345D01*
X48766Y405179D01*
X48474Y405137D01*
X48141Y405220D01*
X47891Y405429D01*
X47641Y405804D01*
G01X46391Y404637D02*
X46141Y404429D01*
X45849Y404304D01*
X45474Y404262D01*
X45099Y404345D01*
X44807Y404512D01*
X44599Y404804D01*
X44557Y405137D01*
X44641Y405470D01*
X44849Y405679D01*
X45141Y405845D01*
X45432Y405887D01*
X45724Y405845D01*
X46099Y405679D01*
X45974Y406762D01*
X44849D01*
G01X61800Y372300D02*
Y369800D01*
G01X62758Y372300D02*
X60842D01*
G01X59633Y369800D02*
Y372300D01*
X58633D01*
X58300Y372175D01*
X58050Y371883D01*
X57967Y371550D01*
X58050Y371217D01*
X58258Y370967D01*
X58633Y370842D01*
X59633D01*
G01X56508Y370092D02*
X56217Y369883D01*
X55883Y369800D01*
X55550Y369883D01*
X55258Y370133D01*
X55050Y370508D01*
X54967Y370883D01*
Y371342D01*
X55050Y371717D01*
X55258Y372050D01*
X55508Y372217D01*
X55800Y372300D01*
X56133Y372217D01*
X56383Y372050D01*
X56550Y371800D01*
X56633Y371467D01*
X56550Y371175D01*
X56342Y370883D01*
X56092Y370717D01*
X55800Y370675D01*
X55467Y370758D01*
X55217Y370967D01*
X54967Y371342D01*
G01X52800Y369800D02*
X52508Y369842D01*
X52175Y369967D01*
X51967Y370175D01*
X51883Y370467D01*
X51967Y370758D01*
X52217Y371008D01*
X52592Y371133D01*
X53008D01*
X53258Y371217D01*
X53467Y371425D01*
X53550Y371717D01*
X53425Y372008D01*
X53133Y372217D01*
X52800Y372300D01*
X52467Y372217D01*
X52175Y372008D01*
X52050Y371717D01*
X52133Y371425D01*
X52342Y371217D01*
X52592Y371133D01*
X53008D01*
X53383Y371008D01*
X53633Y370758D01*
X53717Y370467D01*
X53633Y370175D01*
X53425Y369967D01*
X53092Y369842D01*
X52800Y369800D01*
G01X91117Y368707D02*
Y366207D01*
G01X92075Y368707D02*
X90159D01*
G01X88950Y366207D02*
Y368707D01*
X87950D01*
X87617Y368582D01*
X87367Y368290D01*
X87284Y367957D01*
X87367Y367624D01*
X87575Y367374D01*
X87950Y367249D01*
X88950D01*
G01X85117Y366207D02*
Y368707D01*
X85617Y368207D01*
G01Y366207D02*
X84617D01*
G01X82117Y368707D02*
X82450Y368624D01*
X82700Y368415D01*
X82867Y368165D01*
X82992Y367832D01*
X83034Y367457D01*
X82992Y367082D01*
X82867Y366749D01*
X82700Y366499D01*
X82450Y366290D01*
X82117Y366207D01*
X81784Y366290D01*
X81534Y366499D01*
X81367Y366749D01*
X81242Y367082D01*
X81200Y367457D01*
X81242Y367832D01*
X81367Y368165D01*
X81534Y368415D01*
X81784Y368624D01*
X82117Y368707D01*
G01X79117D02*
X79450Y368624D01*
X79700Y368415D01*
X79867Y368165D01*
X79992Y367832D01*
X80034Y367457D01*
X79992Y367082D01*
X79867Y366749D01*
X79700Y366499D01*
X79450Y366290D01*
X79117Y366207D01*
X78784Y366290D01*
X78534Y366499D01*
X78367Y366749D01*
X78242Y367082D01*
X78200Y367457D01*
X78242Y367832D01*
X78367Y368165D01*
X78534Y368415D01*
X78784Y368624D01*
X79117Y368707D01*
G01X75853Y397381D02*
Y394881D01*
G01X76811Y397381D02*
X74895D01*
G01X73686Y394881D02*
Y397381D01*
X72686D01*
X72353Y397256D01*
X72103Y396964D01*
X72020Y396631D01*
X72103Y396298D01*
X72311Y396048D01*
X72686Y395923D01*
X73686D01*
G01X69853Y394881D02*
Y397381D01*
X70353Y396881D01*
G01Y394881D02*
X69353D01*
G01X66853Y397381D02*
X67186Y397298D01*
X67436Y397089D01*
X67603Y396839D01*
X67728Y396506D01*
X67770Y396131D01*
X67728Y395756D01*
X67603Y395423D01*
X67436Y395173D01*
X67186Y394964D01*
X66853Y394881D01*
X66520Y394964D01*
X66270Y395173D01*
X66103Y395423D01*
X65978Y395756D01*
X65936Y396131D01*
X65978Y396506D01*
X66103Y396839D01*
X66270Y397089D01*
X66520Y397298D01*
X66853Y397381D01*
G01X64645Y396964D02*
X64395Y397214D01*
X64103Y397339D01*
X63770Y397381D01*
X63353Y397298D01*
X63061Y397089D01*
X62978Y396839D01*
X63020Y396589D01*
X63186Y396381D01*
X64020Y395964D01*
X64395Y395673D01*
X64645Y395256D01*
X64728Y394881D01*
X62978D01*
G01X87900Y354900D02*
Y352400D01*
G01X88858Y354900D02*
X86942D01*
G01X85733Y352400D02*
Y354900D01*
X84733D01*
X84400Y354775D01*
X84150Y354483D01*
X84067Y354150D01*
X84150Y353817D01*
X84358Y353567D01*
X84733Y353442D01*
X85733D01*
G01X81983Y352400D02*
X81900Y352942D01*
X81775Y353400D01*
X81608Y353817D01*
X81400Y354275D01*
X81067Y354900D01*
X82733D01*
G01X79692Y354483D02*
X79442Y354733D01*
X79150Y354858D01*
X78817Y354900D01*
X78400Y354817D01*
X78108Y354608D01*
X78025Y354358D01*
X78067Y354108D01*
X78233Y353900D01*
X79067Y353483D01*
X79442Y353192D01*
X79692Y352775D01*
X79775Y352400D01*
X78025D01*
G01X86703Y360072D02*
Y357572D01*
G01X87661Y360072D02*
X85745D01*
G01X84536Y357572D02*
Y360072D01*
X83536D01*
X83203Y359947D01*
X82953Y359655D01*
X82870Y359322D01*
X82953Y358989D01*
X83161Y358739D01*
X83536Y358614D01*
X84536D01*
G01X80786Y357572D02*
X80703Y358114D01*
X80578Y358572D01*
X80411Y358989D01*
X80203Y359447D01*
X79870Y360072D01*
X81536D01*
G01X77203Y357572D02*
Y360072D01*
X78745Y358280D01*
X76661D01*
G01X74100Y358100D02*
Y355600D01*
G01X75058Y358100D02*
X73142D01*
G01X71933Y355600D02*
Y358100D01*
X70933D01*
X70600Y357975D01*
X70350Y357683D01*
X70267Y357350D01*
X70350Y357017D01*
X70558Y356767D01*
X70933Y356642D01*
X71933D01*
G01X68183Y355600D02*
X68100Y356142D01*
X67975Y356600D01*
X67808Y357017D01*
X67600Y357475D01*
X67267Y358100D01*
X68933D01*
G01X66017Y355975D02*
X65767Y355767D01*
X65475Y355642D01*
X65100Y355600D01*
X64725Y355683D01*
X64433Y355850D01*
X64225Y356142D01*
X64183Y356475D01*
X64267Y356808D01*
X64475Y357017D01*
X64767Y357183D01*
X65058Y357225D01*
X65350Y357183D01*
X65725Y357017D01*
X65600Y358100D01*
X64475D01*
G01X73600Y363200D02*
Y360700D01*
G01X74558Y363200D02*
X72642D01*
G01X71433Y360700D02*
Y363200D01*
X70433D01*
X70100Y363075D01*
X69850Y362783D01*
X69767Y362450D01*
X69850Y362117D01*
X70058Y361867D01*
X70433Y361742D01*
X71433D01*
G01X67683Y360700D02*
X67600Y361242D01*
X67475Y361700D01*
X67308Y362117D01*
X67100Y362575D01*
X66767Y363200D01*
X68433D01*
G01X65392Y361742D02*
X65100Y362033D01*
X64850Y362200D01*
X64517Y362283D01*
X64225Y362200D01*
X64017Y362033D01*
X63850Y361783D01*
X63808Y361492D01*
X63850Y361242D01*
X64017Y360992D01*
X64267Y360783D01*
X64558Y360700D01*
X64892Y360783D01*
X65183Y361033D01*
X65350Y361408D01*
X65392Y361825D01*
X65308Y362367D01*
X65183Y362658D01*
X64975Y362950D01*
X64683Y363158D01*
X64392Y363200D01*
X64100Y363117D01*
X63892Y362908D01*
G01X88012Y364419D02*
Y361919D01*
G01X88970Y364419D02*
X87054D01*
G01X85845Y361919D02*
Y364419D01*
X84845D01*
X84512Y364294D01*
X84262Y364002D01*
X84179Y363669D01*
X84262Y363336D01*
X84470Y363086D01*
X84845Y362961D01*
X85845D01*
G01X82095Y361919D02*
X82012Y362461D01*
X81887Y362919D01*
X81720Y363336D01*
X81512Y363794D01*
X81179Y364419D01*
X82845D01*
G01X79095Y361919D02*
X79012Y362461D01*
X78887Y362919D01*
X78720Y363336D01*
X78512Y363794D01*
X78179Y364419D01*
X79845D01*
G01X70133Y440800D02*
Y443300D01*
X69092D01*
X68758Y443175D01*
X68550Y443008D01*
X68467Y442675D01*
X68550Y442342D01*
X68800Y442133D01*
X69092Y442008D01*
X70133D01*
G01X69092D02*
X68467Y440800D01*
G01X66383D02*
X66300Y441342D01*
X66175Y441800D01*
X66008Y442217D01*
X65800Y442675D01*
X65467Y443300D01*
X67133D01*
G01X64092Y442883D02*
X63842Y443133D01*
X63550Y443258D01*
X63217Y443300D01*
X62800Y443217D01*
X62508Y443008D01*
X62425Y442758D01*
X62467Y442508D01*
X62633Y442300D01*
X63467Y441883D01*
X63842Y441592D01*
X64092Y441175D01*
X64175Y440800D01*
X62425D01*
G01X70533Y450100D02*
Y452600D01*
X69492D01*
X69158Y452475D01*
X68950Y452308D01*
X68867Y451975D01*
X68950Y451642D01*
X69200Y451433D01*
X69492Y451308D01*
X70533D01*
G01X69492D02*
X68867Y450100D01*
G01X66200D02*
Y452600D01*
X67742Y450808D01*
X65658D01*
G01X64617Y450475D02*
X64367Y450267D01*
X64075Y450142D01*
X63700Y450100D01*
X63325Y450183D01*
X63033Y450350D01*
X62825Y450642D01*
X62783Y450975D01*
X62867Y451308D01*
X63075Y451517D01*
X63367Y451683D01*
X63658Y451725D01*
X63950Y451683D01*
X64325Y451517D01*
X64200Y452600D01*
X63075D01*
G01X70433Y454600D02*
Y457100D01*
X69392D01*
X69058Y456975D01*
X68850Y456808D01*
X68767Y456475D01*
X68850Y456142D01*
X69100Y455933D01*
X69392Y455808D01*
X70433D01*
G01X69392D02*
X68767Y454600D01*
G01X66100D02*
Y457100D01*
X67642Y455308D01*
X65558D01*
G01X63100Y454600D02*
Y457100D01*
X64642Y455308D01*
X62558D01*
G01X53685Y469980D02*
Y472480D01*
X52644D01*
X52310Y472355D01*
X52102Y472188D01*
X52019Y471855D01*
X52102Y471522D01*
X52352Y471313D01*
X52644Y471188D01*
X53685D01*
G01X52644D02*
X52019Y469980D01*
G01X49852D02*
Y472480D01*
X50352Y471980D01*
G01Y469980D02*
X49352D01*
G01X47769Y470480D02*
X47519Y470188D01*
X47185Y470022D01*
X46810Y469980D01*
X46477Y470022D01*
X46144Y470230D01*
X45935Y470480D01*
X45894Y470730D01*
X45977Y471022D01*
X46269Y471230D01*
X46560Y471313D01*
X46935D01*
G01X46560D02*
X46310Y471438D01*
X46102Y471647D01*
X46019Y471897D01*
X46102Y472147D01*
X46310Y472355D01*
X46685Y472480D01*
X47060Y472438D01*
X47435Y472272D01*
G01X80489Y418032D02*
Y420532D01*
X79448D01*
X79114Y420407D01*
X78906Y420240D01*
X78823Y419907D01*
X78906Y419574D01*
X79156Y419365D01*
X79448Y419240D01*
X80489D01*
G01X79448D02*
X78823Y418032D01*
G01X77448Y420115D02*
X77198Y420365D01*
X76906Y420490D01*
X76573Y420532D01*
X76156Y420449D01*
X75864Y420240D01*
X75781Y419990D01*
X75823Y419740D01*
X75989Y419532D01*
X76823Y419115D01*
X77198Y418824D01*
X77448Y418407D01*
X77531Y418032D01*
X75781D01*
G01X73656D02*
X73364Y418074D01*
X73031Y418199D01*
X72823Y418407D01*
X72739Y418699D01*
X72823Y418990D01*
X73073Y419240D01*
X73448Y419365D01*
X73864D01*
X74114Y419449D01*
X74323Y419657D01*
X74406Y419949D01*
X74281Y420240D01*
X73989Y420449D01*
X73656Y420532D01*
X73323Y420449D01*
X73031Y420240D01*
X72906Y419949D01*
X72989Y419657D01*
X73198Y419449D01*
X73448Y419365D01*
X73864D01*
X74239Y419240D01*
X74489Y418990D01*
X74573Y418699D01*
X74489Y418407D01*
X74281Y418199D01*
X73948Y418074D01*
X73656Y418032D01*
G01X31700Y487000D02*
Y484500D01*
G01X32658Y487000D02*
X30742D01*
G01X29533Y484500D02*
Y487000D01*
X28533D01*
X28200Y486875D01*
X27950Y486583D01*
X27867Y486250D01*
X27950Y485917D01*
X28158Y485667D01*
X28533Y485542D01*
X29533D01*
G01X25700Y484500D02*
X25408Y484542D01*
X25075Y484667D01*
X24867Y484875D01*
X24783Y485167D01*
X24867Y485458D01*
X25117Y485708D01*
X25492Y485833D01*
X25908D01*
X26158Y485917D01*
X26367Y486125D01*
X26450Y486417D01*
X26325Y486708D01*
X26033Y486917D01*
X25700Y487000D01*
X25367Y486917D01*
X25075Y486708D01*
X24950Y486417D01*
X25033Y486125D01*
X25242Y485917D01*
X25492Y485833D01*
X25908D01*
X26283Y485708D01*
X26533Y485458D01*
X26617Y485167D01*
X26533Y484875D01*
X26325Y484667D01*
X25992Y484542D01*
X25700Y484500D01*
G01X22700Y487000D02*
X23033Y486917D01*
X23283Y486708D01*
X23450Y486458D01*
X23575Y486125D01*
X23617Y485750D01*
X23575Y485375D01*
X23450Y485042D01*
X23283Y484792D01*
X23033Y484583D01*
X22700Y484500D01*
X22367Y484583D01*
X22117Y484792D01*
X21950Y485042D01*
X21825Y485375D01*
X21783Y485750D01*
X21825Y486125D01*
X21950Y486458D01*
X22117Y486708D01*
X22367Y486917D01*
X22700Y487000D01*
G01X61400Y422200D02*
Y419700D01*
G01X62358Y422200D02*
X60442D01*
G01X59233Y419700D02*
Y422200D01*
X58233D01*
X57900Y422075D01*
X57650Y421783D01*
X57567Y421450D01*
X57650Y421117D01*
X57858Y420867D01*
X58233Y420742D01*
X59233D01*
G01X56108Y419992D02*
X55817Y419783D01*
X55483Y419700D01*
X55150Y419783D01*
X54858Y420033D01*
X54650Y420408D01*
X54567Y420783D01*
Y421242D01*
X54650Y421617D01*
X54858Y421950D01*
X55108Y422117D01*
X55400Y422200D01*
X55733Y422117D01*
X55983Y421950D01*
X56150Y421700D01*
X56233Y421367D01*
X56150Y421075D01*
X55942Y420783D01*
X55692Y420617D01*
X55400Y420575D01*
X55067Y420658D01*
X54817Y420867D01*
X54567Y421242D01*
G01X53192Y421783D02*
X52942Y422033D01*
X52650Y422158D01*
X52317Y422200D01*
X51900Y422117D01*
X51608Y421908D01*
X51525Y421658D01*
X51567Y421408D01*
X51733Y421200D01*
X52567Y420783D01*
X52942Y420492D01*
X53192Y420075D01*
X53275Y419700D01*
X51525D01*
G01X16480Y475433D02*
Y472933D01*
G01X17438Y475433D02*
X15522D01*
G01X14313Y472933D02*
Y475433D01*
X13313D01*
X12980Y475308D01*
X12730Y475016D01*
X12647Y474683D01*
X12730Y474350D01*
X12938Y474100D01*
X13313Y473975D01*
X14313D01*
G01X11188Y473225D02*
X10897Y473016D01*
X10563Y472933D01*
X10230Y473016D01*
X9938Y473266D01*
X9730Y473641D01*
X9647Y474016D01*
Y474475D01*
X9730Y474850D01*
X9938Y475183D01*
X10188Y475350D01*
X10480Y475433D01*
X10813Y475350D01*
X11063Y475183D01*
X11230Y474933D01*
X11313Y474600D01*
X11230Y474308D01*
X11022Y474016D01*
X10772Y473850D01*
X10480Y473808D01*
X10147Y473891D01*
X9897Y474100D01*
X9647Y474475D01*
G01X77900Y458500D02*
X75400D01*
G01X77900Y457542D02*
Y459458D01*
G01X75400Y460667D02*
X77900D01*
Y461667D01*
X77775Y462000D01*
X77483Y462250D01*
X77150Y462333D01*
X76817Y462250D01*
X76567Y462042D01*
X76442Y461667D01*
Y460667D01*
G01X75400Y464500D02*
X75442Y464792D01*
X75567Y465125D01*
X75775Y465333D01*
X76067Y465417D01*
X76358Y465333D01*
X76608Y465083D01*
X76733Y464708D01*
Y464292D01*
X76817Y464042D01*
X77025Y463833D01*
X77317Y463750D01*
X77608Y463875D01*
X77817Y464167D01*
X77900Y464500D01*
X77817Y464833D01*
X77608Y465125D01*
X77317Y465250D01*
X77025Y465167D01*
X76817Y464958D01*
X76733Y464708D01*
Y464292D01*
X76608Y463917D01*
X76358Y463667D01*
X76067Y463583D01*
X75775Y463667D01*
X75567Y463875D01*
X75442Y464208D01*
X75400Y464500D01*
G01X77491Y447340D02*
Y444840D01*
G01X78449Y447340D02*
X76533D01*
G01X75324Y444840D02*
Y447340D01*
X74324D01*
X73991Y447215D01*
X73741Y446923D01*
X73658Y446590D01*
X73741Y446257D01*
X73949Y446007D01*
X74324Y445882D01*
X75324D01*
G01X72199Y445132D02*
X71908Y444923D01*
X71574Y444840D01*
X71241Y444923D01*
X70949Y445173D01*
X70741Y445548D01*
X70658Y445923D01*
Y446382D01*
X70741Y446757D01*
X70949Y447090D01*
X71199Y447257D01*
X71491Y447340D01*
X71824Y447257D01*
X72074Y447090D01*
X72241Y446840D01*
X72324Y446507D01*
X72241Y446215D01*
X72033Y445923D01*
X71783Y445757D01*
X71491Y445715D01*
X71158Y445798D01*
X70908Y446007D01*
X70658Y446382D01*
G01X68491Y447340D02*
X68824Y447257D01*
X69074Y447048D01*
X69241Y446798D01*
X69366Y446465D01*
X69408Y446090D01*
X69366Y445715D01*
X69241Y445382D01*
X69074Y445132D01*
X68824Y444923D01*
X68491Y444840D01*
X68158Y444923D01*
X67908Y445132D01*
X67741Y445382D01*
X67616Y445715D01*
X67574Y446090D01*
X67616Y446465D01*
X67741Y446798D01*
X67908Y447048D01*
X68158Y447257D01*
X68491Y447340D01*
G01X70360Y479929D02*
Y477429D01*
G01X71318Y479929D02*
X69402D01*
G01X68193Y477429D02*
Y479929D01*
X67193D01*
X66860Y479804D01*
X66610Y479512D01*
X66527Y479179D01*
X66610Y478846D01*
X66818Y478596D01*
X67193Y478471D01*
X68193D01*
G01X64360Y477429D02*
X64068Y477471D01*
X63735Y477596D01*
X63527Y477804D01*
X63443Y478096D01*
X63527Y478387D01*
X63777Y478637D01*
X64152Y478762D01*
X64568D01*
X64818Y478846D01*
X65027Y479054D01*
X65110Y479346D01*
X64985Y479637D01*
X64693Y479846D01*
X64360Y479929D01*
X64027Y479846D01*
X63735Y479637D01*
X63610Y479346D01*
X63693Y479054D01*
X63902Y478846D01*
X64152Y478762D01*
X64568D01*
X64943Y478637D01*
X65193Y478387D01*
X65277Y478096D01*
X65193Y477804D01*
X64985Y477596D01*
X64652Y477471D01*
X64360Y477429D01*
G01X61360D02*
X61068Y477471D01*
X60735Y477596D01*
X60527Y477804D01*
X60443Y478096D01*
X60527Y478387D01*
X60777Y478637D01*
X61152Y478762D01*
X61568D01*
X61818Y478846D01*
X62027Y479054D01*
X62110Y479346D01*
X61985Y479637D01*
X61693Y479846D01*
X61360Y479929D01*
X61027Y479846D01*
X60735Y479637D01*
X60610Y479346D01*
X60693Y479054D01*
X60902Y478846D01*
X61152Y478762D01*
X61568D01*
X61943Y478637D01*
X62193Y478387D01*
X62277Y478096D01*
X62193Y477804D01*
X61985Y477596D01*
X61652Y477471D01*
X61360Y477429D01*
G01X69893Y468994D02*
Y466494D01*
G01X70851Y468994D02*
X68935D01*
G01X67726Y466494D02*
Y468994D01*
X66726D01*
X66393Y468869D01*
X66143Y468577D01*
X66060Y468244D01*
X66143Y467911D01*
X66351Y467661D01*
X66726Y467536D01*
X67726D01*
G01X63893Y466494D02*
X63601Y466536D01*
X63268Y466661D01*
X63060Y466869D01*
X62976Y467161D01*
X63060Y467452D01*
X63310Y467702D01*
X63685Y467827D01*
X64101D01*
X64351Y467911D01*
X64560Y468119D01*
X64643Y468411D01*
X64518Y468702D01*
X64226Y468911D01*
X63893Y468994D01*
X63560Y468911D01*
X63268Y468702D01*
X63143Y468411D01*
X63226Y468119D01*
X63435Y467911D01*
X63685Y467827D01*
X64101D01*
X64476Y467702D01*
X64726Y467452D01*
X64810Y467161D01*
X64726Y466869D01*
X64518Y466661D01*
X64185Y466536D01*
X63893Y466494D01*
G01X60976D02*
X60893Y467036D01*
X60768Y467494D01*
X60601Y467911D01*
X60393Y468369D01*
X60060Y468994D01*
X61726D01*
G01X29718Y475919D02*
Y473419D01*
G01X30676Y475919D02*
X28760D01*
G01X27551Y473419D02*
Y475919D01*
X26551D01*
X26218Y475794D01*
X25968Y475502D01*
X25885Y475169D01*
X25968Y474836D01*
X26176Y474586D01*
X26551Y474461D01*
X27551D01*
G01X23718Y473419D02*
X23426Y473461D01*
X23093Y473586D01*
X22885Y473794D01*
X22801Y474086D01*
X22885Y474377D01*
X23135Y474627D01*
X23510Y474752D01*
X23926D01*
X24176Y474836D01*
X24385Y475044D01*
X24468Y475336D01*
X24343Y475627D01*
X24051Y475836D01*
X23718Y475919D01*
X23385Y475836D01*
X23093Y475627D01*
X22968Y475336D01*
X23051Y475044D01*
X23260Y474836D01*
X23510Y474752D01*
X23926D01*
X24301Y474627D01*
X24551Y474377D01*
X24635Y474086D01*
X24551Y473794D01*
X24343Y473586D01*
X24010Y473461D01*
X23718Y473419D01*
G01X21510Y474461D02*
X21218Y474752D01*
X20968Y474919D01*
X20635Y475002D01*
X20343Y474919D01*
X20135Y474752D01*
X19968Y474502D01*
X19926Y474211D01*
X19968Y473961D01*
X20135Y473711D01*
X20385Y473502D01*
X20676Y473419D01*
X21010Y473502D01*
X21301Y473752D01*
X21468Y474127D01*
X21510Y474544D01*
X21426Y475086D01*
X21301Y475377D01*
X21093Y475669D01*
X20801Y475877D01*
X20510Y475919D01*
X20218Y475836D01*
X20010Y475627D01*
G01X28700Y481900D02*
Y479400D01*
G01X29658Y481900D02*
X27742D01*
G01X26533Y479400D02*
Y481900D01*
X25533D01*
X25200Y481775D01*
X24950Y481483D01*
X24867Y481150D01*
X24950Y480817D01*
X25158Y480567D01*
X25533Y480442D01*
X26533D01*
G01X22700Y479400D02*
X22408Y479442D01*
X22075Y479567D01*
X21867Y479775D01*
X21783Y480067D01*
X21867Y480358D01*
X22117Y480608D01*
X22492Y480733D01*
X22908D01*
X23158Y480817D01*
X23367Y481025D01*
X23450Y481317D01*
X23325Y481608D01*
X23033Y481817D01*
X22700Y481900D01*
X22367Y481817D01*
X22075Y481608D01*
X21950Y481317D01*
X22033Y481025D01*
X22242Y480817D01*
X22492Y480733D01*
X22908D01*
X23283Y480608D01*
X23533Y480358D01*
X23617Y480067D01*
X23533Y479775D01*
X23325Y479567D01*
X22992Y479442D01*
X22700Y479400D01*
G01X20617Y479775D02*
X20367Y479567D01*
X20075Y479442D01*
X19700Y479400D01*
X19325Y479483D01*
X19033Y479650D01*
X18825Y479942D01*
X18783Y480275D01*
X18867Y480608D01*
X19075Y480817D01*
X19367Y480983D01*
X19658Y481025D01*
X19950Y480983D01*
X20325Y480817D01*
X20200Y481900D01*
X19075D01*
G01X31890Y469921D02*
Y467421D01*
G01X32848Y469921D02*
X30932D01*
G01X29723Y467421D02*
Y469921D01*
X28723D01*
X28390Y469796D01*
X28140Y469504D01*
X28057Y469171D01*
X28140Y468838D01*
X28348Y468588D01*
X28723Y468463D01*
X29723D01*
G01X25890Y467421D02*
X25598Y467463D01*
X25265Y467588D01*
X25057Y467796D01*
X24973Y468088D01*
X25057Y468379D01*
X25307Y468629D01*
X25682Y468754D01*
X26098D01*
X26348Y468838D01*
X26557Y469046D01*
X26640Y469338D01*
X26515Y469629D01*
X26223Y469838D01*
X25890Y469921D01*
X25557Y469838D01*
X25265Y469629D01*
X25140Y469338D01*
X25223Y469046D01*
X25432Y468838D01*
X25682Y468754D01*
X26098D01*
X26473Y468629D01*
X26723Y468379D01*
X26807Y468088D01*
X26723Y467796D01*
X26515Y467588D01*
X26182Y467463D01*
X25890Y467421D01*
G01X22390D02*
Y469921D01*
X23932Y468129D01*
X21848D01*
G01X28128Y464787D02*
Y462287D01*
G01X29086Y464787D02*
X27170D01*
G01X25961Y462287D02*
Y464787D01*
X24961D01*
X24628Y464662D01*
X24378Y464370D01*
X24295Y464037D01*
X24378Y463704D01*
X24586Y463454D01*
X24961Y463329D01*
X25961D01*
G01X22128Y462287D02*
X21836Y462329D01*
X21503Y462454D01*
X21295Y462662D01*
X21211Y462954D01*
X21295Y463245D01*
X21545Y463495D01*
X21920Y463620D01*
X22336D01*
X22586Y463704D01*
X22795Y463912D01*
X22878Y464204D01*
X22753Y464495D01*
X22461Y464704D01*
X22128Y464787D01*
X21795Y464704D01*
X21503Y464495D01*
X21378Y464204D01*
X21461Y463912D01*
X21670Y463704D01*
X21920Y463620D01*
X22336D01*
X22711Y463495D01*
X22961Y463245D01*
X23045Y462954D01*
X22961Y462662D01*
X22753Y462454D01*
X22420Y462329D01*
X22128Y462287D01*
G01X20045Y462787D02*
X19795Y462495D01*
X19461Y462329D01*
X19086Y462287D01*
X18753Y462329D01*
X18420Y462537D01*
X18211Y462787D01*
X18170Y463037D01*
X18253Y463329D01*
X18545Y463537D01*
X18836Y463620D01*
X19211D01*
G01X18836D02*
X18586Y463745D01*
X18378Y463954D01*
X18295Y464204D01*
X18378Y464454D01*
X18586Y464662D01*
X18961Y464787D01*
X19336Y464745D01*
X19711Y464579D01*
G01X69805Y465385D02*
Y462885D01*
G01X70763Y465385D02*
X68847D01*
G01X67638Y462885D02*
Y465385D01*
X66638D01*
X66305Y465260D01*
X66055Y464968D01*
X65972Y464635D01*
X66055Y464302D01*
X66263Y464052D01*
X66638Y463927D01*
X67638D01*
G01X63805Y462885D02*
X63513Y462927D01*
X63180Y463052D01*
X62972Y463260D01*
X62888Y463552D01*
X62972Y463843D01*
X63222Y464093D01*
X63597Y464218D01*
X64013D01*
X64263Y464302D01*
X64472Y464510D01*
X64555Y464802D01*
X64430Y465093D01*
X64138Y465302D01*
X63805Y465385D01*
X63472Y465302D01*
X63180Y465093D01*
X63055Y464802D01*
X63138Y464510D01*
X63347Y464302D01*
X63597Y464218D01*
X64013D01*
X64388Y464093D01*
X64638Y463843D01*
X64722Y463552D01*
X64638Y463260D01*
X64430Y463052D01*
X64097Y462927D01*
X63805Y462885D01*
G01X61597Y464968D02*
X61347Y465218D01*
X61055Y465343D01*
X60722Y465385D01*
X60305Y465302D01*
X60013Y465093D01*
X59930Y464843D01*
X59972Y464593D01*
X60138Y464385D01*
X60972Y463968D01*
X61347Y463677D01*
X61597Y463260D01*
X61680Y462885D01*
X59930D01*
G01X71257Y476341D02*
Y473841D01*
G01X72215Y476341D02*
X70299D01*
G01X69090Y473841D02*
Y476341D01*
X68090D01*
X67757Y476216D01*
X67507Y475924D01*
X67424Y475591D01*
X67507Y475258D01*
X67715Y475008D01*
X68090Y474883D01*
X69090D01*
G01X65257Y473841D02*
X64965Y473883D01*
X64632Y474008D01*
X64424Y474216D01*
X64340Y474508D01*
X64424Y474799D01*
X64674Y475049D01*
X65049Y475174D01*
X65465D01*
X65715Y475258D01*
X65924Y475466D01*
X66007Y475758D01*
X65882Y476049D01*
X65590Y476258D01*
X65257Y476341D01*
X64924Y476258D01*
X64632Y476049D01*
X64507Y475758D01*
X64590Y475466D01*
X64799Y475258D01*
X65049Y475174D01*
X65465D01*
X65840Y475049D01*
X66090Y474799D01*
X66174Y474508D01*
X66090Y474216D01*
X65882Y474008D01*
X65549Y473883D01*
X65257Y473841D01*
G01X62257D02*
Y476341D01*
X62757Y475841D01*
G01Y473841D02*
X61757D01*
G01X50598Y432335D02*
X48098D01*
G01X50598Y431377D02*
Y433293D01*
G01X48098Y434502D02*
X50598D01*
Y435502D01*
X50473Y435835D01*
X50181Y436085D01*
X49848Y436168D01*
X49515Y436085D01*
X49265Y435877D01*
X49140Y435502D01*
Y434502D01*
G01X48098Y438335D02*
X50598D01*
X50098Y437835D01*
G01X48098D02*
Y438835D01*
G01X50598Y441335D02*
X50515Y441002D01*
X50306Y440752D01*
X50056Y440585D01*
X49723Y440460D01*
X49348Y440418D01*
X48973Y440460D01*
X48640Y440585D01*
X48390Y440752D01*
X48181Y441002D01*
X48098Y441335D01*
X48181Y441668D01*
X48390Y441918D01*
X48640Y442085D01*
X48973Y442210D01*
X49348Y442252D01*
X49723Y442210D01*
X50056Y442085D01*
X50306Y441918D01*
X50515Y441668D01*
X50598Y441335D01*
G01X48473Y443418D02*
X48265Y443668D01*
X48140Y443960D01*
X48098Y444335D01*
X48181Y444710D01*
X48348Y445002D01*
X48640Y445210D01*
X48973Y445252D01*
X49306Y445168D01*
X49515Y444960D01*
X49681Y444668D01*
X49723Y444377D01*
X49681Y444085D01*
X49515Y443710D01*
X50598Y443835D01*
Y444960D01*
G01X31172Y458354D02*
Y455854D01*
G01X32130Y458354D02*
X30214D01*
G01X29005Y455854D02*
Y458354D01*
X28005D01*
X27672Y458229D01*
X27422Y457937D01*
X27339Y457604D01*
X27422Y457271D01*
X27630Y457021D01*
X28005Y456896D01*
X29005D01*
G01X25172Y455854D02*
Y458354D01*
X25672Y457854D01*
G01Y455854D02*
X24672D01*
G01X22172Y458354D02*
X22505Y458271D01*
X22755Y458062D01*
X22922Y457812D01*
X23047Y457479D01*
X23089Y457104D01*
X23047Y456729D01*
X22922Y456396D01*
X22755Y456146D01*
X22505Y455937D01*
X22172Y455854D01*
X21839Y455937D01*
X21589Y456146D01*
X21422Y456396D01*
X21297Y456729D01*
X21255Y457104D01*
X21297Y457479D01*
X21422Y457812D01*
X21589Y458062D01*
X21839Y458271D01*
X22172Y458354D01*
G01X19964Y456896D02*
X19672Y457187D01*
X19422Y457354D01*
X19089Y457437D01*
X18797Y457354D01*
X18589Y457187D01*
X18422Y456937D01*
X18380Y456646D01*
X18422Y456396D01*
X18589Y456146D01*
X18839Y455937D01*
X19130Y455854D01*
X19464Y455937D01*
X19755Y456187D01*
X19922Y456562D01*
X19964Y456979D01*
X19880Y457521D01*
X19755Y457812D01*
X19547Y458104D01*
X19255Y458312D01*
X18964Y458354D01*
X18672Y458271D01*
X18464Y458062D01*
G01X47596Y451608D02*
X45096D01*
G01X47596Y450650D02*
Y452566D01*
G01X45096Y453775D02*
X47596D01*
Y454775D01*
X47471Y455108D01*
X47179Y455358D01*
X46846Y455441D01*
X46513Y455358D01*
X46263Y455150D01*
X46138Y454775D01*
Y453775D01*
G01X45096Y457608D02*
X47596D01*
X47096Y457108D01*
G01X45096D02*
Y458108D01*
G01X47596Y460608D02*
X47513Y460275D01*
X47304Y460025D01*
X47054Y459858D01*
X46721Y459733D01*
X46346Y459691D01*
X45971Y459733D01*
X45638Y459858D01*
X45388Y460025D01*
X45179Y460275D01*
X45096Y460608D01*
X45179Y460941D01*
X45388Y461191D01*
X45638Y461358D01*
X45971Y461483D01*
X46346Y461525D01*
X46721Y461483D01*
X47054Y461358D01*
X47304Y461191D01*
X47513Y460941D01*
X47596Y460608D01*
G01X45096Y463608D02*
X45138Y463900D01*
X45263Y464233D01*
X45471Y464441D01*
X45763Y464525D01*
X46054Y464441D01*
X46304Y464191D01*
X46429Y463816D01*
Y463400D01*
X46513Y463150D01*
X46721Y462941D01*
X47013Y462858D01*
X47304Y462983D01*
X47513Y463275D01*
X47596Y463608D01*
X47513Y463941D01*
X47304Y464233D01*
X47013Y464358D01*
X46721Y464275D01*
X46513Y464066D01*
X46429Y463816D01*
Y463400D01*
X46304Y463025D01*
X46054Y462775D01*
X45763Y462691D01*
X45471Y462775D01*
X45263Y462983D01*
X45138Y463316D01*
X45096Y463608D01*
G01X35000Y532667D02*
X37500D01*
Y533708D01*
X37375Y534042D01*
X37208Y534250D01*
X36875Y534333D01*
X36542Y534250D01*
X36333Y534000D01*
X36208Y533708D01*
Y532667D01*
G01Y533708D02*
X35000Y534333D01*
G01X37083Y535708D02*
X37333Y535958D01*
X37458Y536250D01*
X37500Y536583D01*
X37417Y537000D01*
X37208Y537292D01*
X36958Y537375D01*
X36708Y537333D01*
X36500Y537167D01*
X36083Y536333D01*
X35792Y535958D01*
X35375Y535708D01*
X35000Y535625D01*
Y537375D01*
G01X37083Y538708D02*
X37333Y538958D01*
X37458Y539250D01*
X37500Y539583D01*
X37417Y540000D01*
X37208Y540292D01*
X36958Y540375D01*
X36708Y540333D01*
X36500Y540167D01*
X36083Y539333D01*
X35792Y538958D01*
X35375Y538708D01*
X35000Y538625D01*
Y540375D01*
G01X35375Y541583D02*
X35167Y541833D01*
X35042Y542125D01*
X35000Y542500D01*
X35083Y542875D01*
X35250Y543167D01*
X35542Y543375D01*
X35875Y543417D01*
X36208Y543333D01*
X36417Y543125D01*
X36583Y542833D01*
X36625Y542542D01*
X36583Y542250D01*
X36417Y541875D01*
X37500Y542000D01*
Y543125D01*
G01X60783Y506192D02*
X61033Y506317D01*
X61325Y506400D01*
X61658D01*
X62033Y506275D01*
X62325Y506067D01*
X62533Y505817D01*
X62700Y505400D01*
X62742Y505025D01*
X62658Y504650D01*
X62533Y504400D01*
X62283Y504150D01*
X61992Y503983D01*
X61700Y503900D01*
X61408D01*
X61117Y503983D01*
X60867Y504108D01*
X60658Y504275D01*
G01X58700Y503900D02*
Y506400D01*
X59200Y505900D01*
G01Y503900D02*
X58200D01*
G01X56492Y505983D02*
X56242Y506233D01*
X55950Y506358D01*
X55617Y506400D01*
X55200Y506317D01*
X54908Y506108D01*
X54825Y505858D01*
X54867Y505608D01*
X55033Y505400D01*
X55867Y504983D01*
X56242Y504692D01*
X56492Y504275D01*
X56575Y503900D01*
X54825D01*
G01X52200D02*
Y506400D01*
X53742Y504608D01*
X51658D01*
G01X46433Y548500D02*
Y551000D01*
X45392D01*
X45058Y550875D01*
X44850Y550708D01*
X44767Y550375D01*
X44850Y550042D01*
X45100Y549833D01*
X45392Y549708D01*
X46433D01*
G01X45392D02*
X44767Y548500D01*
G01X43392Y550583D02*
X43142Y550833D01*
X42850Y550958D01*
X42517Y551000D01*
X42100Y550917D01*
X41808Y550708D01*
X41725Y550458D01*
X41767Y550208D01*
X41933Y550000D01*
X42767Y549583D01*
X43142Y549292D01*
X43392Y548875D01*
X43475Y548500D01*
X41725D01*
G01X40392Y550583D02*
X40142Y550833D01*
X39850Y550958D01*
X39517Y551000D01*
X39100Y550917D01*
X38808Y550708D01*
X38725Y550458D01*
X38767Y550208D01*
X38933Y550000D01*
X39767Y549583D01*
X40142Y549292D01*
X40392Y548875D01*
X40475Y548500D01*
X38725D01*
G01X36683D02*
X36600Y549042D01*
X36475Y549500D01*
X36308Y549917D01*
X36100Y550375D01*
X35767Y551000D01*
X37433D01*
G01X64333Y491100D02*
Y493600D01*
X63292D01*
X62958Y493475D01*
X62750Y493308D01*
X62667Y492975D01*
X62750Y492642D01*
X63000Y492433D01*
X63292Y492308D01*
X64333D01*
G01X63292D02*
X62667Y491100D01*
G01X60500D02*
Y493600D01*
X61000Y493100D01*
G01Y491100D02*
X60000D01*
G01X58417Y491475D02*
X58167Y491267D01*
X57875Y491142D01*
X57500Y491100D01*
X57125Y491183D01*
X56833Y491350D01*
X56625Y491642D01*
X56583Y491975D01*
X56667Y492308D01*
X56875Y492517D01*
X57167Y492683D01*
X57458Y492725D01*
X57750Y492683D01*
X58125Y492517D01*
X58000Y493600D01*
X56875D01*
G01X84133Y530600D02*
Y533100D01*
X83092D01*
X82758Y532975D01*
X82550Y532808D01*
X82467Y532475D01*
X82550Y532142D01*
X82800Y531933D01*
X83092Y531808D01*
X84133D01*
G01X83092D02*
X82467Y530600D01*
G01X81217Y531100D02*
X80967Y530808D01*
X80633Y530642D01*
X80258Y530600D01*
X79925Y530642D01*
X79592Y530850D01*
X79383Y531100D01*
X79342Y531350D01*
X79425Y531642D01*
X79717Y531850D01*
X80008Y531933D01*
X80383D01*
G01X80008D02*
X79758Y532058D01*
X79550Y532267D01*
X79467Y532517D01*
X79550Y532767D01*
X79758Y532975D01*
X80133Y533100D01*
X80508Y533058D01*
X80883Y532892D01*
G01X78092Y532683D02*
X77842Y532933D01*
X77550Y533058D01*
X77217Y533100D01*
X76800Y533017D01*
X76508Y532808D01*
X76425Y532558D01*
X76467Y532308D01*
X76633Y532100D01*
X77467Y531683D01*
X77842Y531392D01*
X78092Y530975D01*
X78175Y530600D01*
X76425D01*
G01X75092Y531642D02*
X74800Y531933D01*
X74550Y532100D01*
X74217Y532183D01*
X73925Y532100D01*
X73717Y531933D01*
X73550Y531683D01*
X73508Y531392D01*
X73550Y531142D01*
X73717Y530892D01*
X73967Y530683D01*
X74258Y530600D01*
X74592Y530683D01*
X74883Y530933D01*
X75050Y531308D01*
X75092Y531725D01*
X75008Y532267D01*
X74883Y532558D01*
X74675Y532850D01*
X74383Y533058D01*
X74092Y533100D01*
X73800Y533017D01*
X73592Y532808D01*
G01X72433Y549700D02*
Y552200D01*
X71392D01*
X71058Y552075D01*
X70850Y551908D01*
X70767Y551575D01*
X70850Y551242D01*
X71100Y551033D01*
X71392Y550908D01*
X72433D01*
G01X71392D02*
X70767Y549700D01*
G01X69517Y550200D02*
X69267Y549908D01*
X68933Y549742D01*
X68558Y549700D01*
X68225Y549742D01*
X67892Y549950D01*
X67683Y550200D01*
X67642Y550450D01*
X67725Y550742D01*
X68017Y550950D01*
X68308Y551033D01*
X68683D01*
G01X68308D02*
X68058Y551158D01*
X67850Y551367D01*
X67767Y551617D01*
X67850Y551867D01*
X68058Y552075D01*
X68433Y552200D01*
X68808Y552158D01*
X69183Y551992D01*
G01X66392Y551783D02*
X66142Y552033D01*
X65850Y552158D01*
X65517Y552200D01*
X65100Y552117D01*
X64808Y551908D01*
X64725Y551658D01*
X64767Y551408D01*
X64933Y551200D01*
X65767Y550783D01*
X66142Y550492D01*
X66392Y550075D01*
X66475Y549700D01*
X64725D01*
G01X63517Y550075D02*
X63267Y549867D01*
X62975Y549742D01*
X62600Y549700D01*
X62225Y549783D01*
X61933Y549950D01*
X61725Y550242D01*
X61683Y550575D01*
X61767Y550908D01*
X61975Y551117D01*
X62267Y551283D01*
X62558Y551325D01*
X62850Y551283D01*
X63225Y551117D01*
X63100Y552200D01*
X61975D01*
G01X58833Y548500D02*
Y551000D01*
X57792D01*
X57458Y550875D01*
X57250Y550708D01*
X57167Y550375D01*
X57250Y550042D01*
X57500Y549833D01*
X57792Y549708D01*
X58833D01*
G01X57792D02*
X57167Y548500D01*
G01X55917Y549000D02*
X55667Y548708D01*
X55333Y548542D01*
X54958Y548500D01*
X54625Y548542D01*
X54292Y548750D01*
X54083Y549000D01*
X54042Y549250D01*
X54125Y549542D01*
X54417Y549750D01*
X54708Y549833D01*
X55083D01*
G01X54708D02*
X54458Y549958D01*
X54250Y550167D01*
X54167Y550417D01*
X54250Y550667D01*
X54458Y550875D01*
X54833Y551000D01*
X55208Y550958D01*
X55583Y550792D01*
G01X52792Y550583D02*
X52542Y550833D01*
X52250Y550958D01*
X51917Y551000D01*
X51500Y550917D01*
X51208Y550708D01*
X51125Y550458D01*
X51167Y550208D01*
X51333Y550000D01*
X52167Y549583D01*
X52542Y549292D01*
X52792Y548875D01*
X52875Y548500D01*
X51125D01*
G01X49917Y549000D02*
X49667Y548708D01*
X49333Y548542D01*
X48958Y548500D01*
X48625Y548542D01*
X48292Y548750D01*
X48083Y549000D01*
X48042Y549250D01*
X48125Y549542D01*
X48417Y549750D01*
X48708Y549833D01*
X49083D01*
G01X48708D02*
X48458Y549958D01*
X48250Y550167D01*
X48167Y550417D01*
X48250Y550667D01*
X48458Y550875D01*
X48833Y551000D01*
X49208Y550958D01*
X49583Y550792D01*
G01X83633Y526200D02*
Y528700D01*
X82592D01*
X82258Y528575D01*
X82050Y528408D01*
X81967Y528075D01*
X82050Y527742D01*
X82300Y527533D01*
X82592Y527408D01*
X83633D01*
G01X82592D02*
X81967Y526200D01*
G01X80717Y526700D02*
X80467Y526408D01*
X80133Y526242D01*
X79758Y526200D01*
X79425Y526242D01*
X79092Y526450D01*
X78883Y526700D01*
X78842Y526950D01*
X78925Y527242D01*
X79217Y527450D01*
X79508Y527533D01*
X79883D01*
G01X79508D02*
X79258Y527658D01*
X79050Y527867D01*
X78967Y528117D01*
X79050Y528367D01*
X79258Y528575D01*
X79633Y528700D01*
X80008Y528658D01*
X80383Y528492D01*
G01X77592Y528283D02*
X77342Y528533D01*
X77050Y528658D01*
X76717Y528700D01*
X76300Y528617D01*
X76008Y528408D01*
X75925Y528158D01*
X75967Y527908D01*
X76133Y527700D01*
X76967Y527283D01*
X77342Y526992D01*
X77592Y526575D01*
X77675Y526200D01*
X75925D01*
G01X74592Y528283D02*
X74342Y528533D01*
X74050Y528658D01*
X73717Y528700D01*
X73300Y528617D01*
X73008Y528408D01*
X72925Y528158D01*
X72967Y527908D01*
X73133Y527700D01*
X73967Y527283D01*
X74342Y526992D01*
X74592Y526575D01*
X74675Y526200D01*
X72925D01*
G01X72433Y554700D02*
Y557200D01*
X71392D01*
X71058Y557075D01*
X70850Y556908D01*
X70767Y556575D01*
X70850Y556242D01*
X71100Y556033D01*
X71392Y555908D01*
X72433D01*
G01X71392D02*
X70767Y554700D01*
G01X69517Y555200D02*
X69267Y554908D01*
X68933Y554742D01*
X68558Y554700D01*
X68225Y554742D01*
X67892Y554950D01*
X67683Y555200D01*
X67642Y555450D01*
X67725Y555742D01*
X68017Y555950D01*
X68308Y556033D01*
X68683D01*
G01X68308D02*
X68058Y556158D01*
X67850Y556367D01*
X67767Y556617D01*
X67850Y556867D01*
X68058Y557075D01*
X68433Y557200D01*
X68808Y557158D01*
X69183Y556992D01*
G01X66517Y555200D02*
X66267Y554908D01*
X65933Y554742D01*
X65558Y554700D01*
X65225Y554742D01*
X64892Y554950D01*
X64683Y555200D01*
X64642Y555450D01*
X64725Y555742D01*
X65017Y555950D01*
X65308Y556033D01*
X65683D01*
G01X65308D02*
X65058Y556158D01*
X64850Y556367D01*
X64767Y556617D01*
X64850Y556867D01*
X65058Y557075D01*
X65433Y557200D01*
X65808Y557158D01*
X66183Y556992D01*
G01X63308Y554992D02*
X63017Y554783D01*
X62683Y554700D01*
X62350Y554783D01*
X62058Y555033D01*
X61850Y555408D01*
X61767Y555783D01*
Y556242D01*
X61850Y556617D01*
X62058Y556950D01*
X62308Y557117D01*
X62600Y557200D01*
X62933Y557117D01*
X63183Y556950D01*
X63350Y556700D01*
X63433Y556367D01*
X63350Y556075D01*
X63142Y555783D01*
X62892Y555617D01*
X62600Y555575D01*
X62267Y555658D01*
X62017Y555867D01*
X61767Y556242D01*
G01X45892Y492017D02*
X46017Y491767D01*
X46100Y491475D01*
Y491142D01*
X45975Y490767D01*
X45767Y490475D01*
X45517Y490267D01*
X45100Y490100D01*
X44725Y490058D01*
X44350Y490142D01*
X44100Y490267D01*
X43850Y490517D01*
X43683Y490808D01*
X43600Y491100D01*
Y491392D01*
X43683Y491683D01*
X43808Y491933D01*
X43975Y492142D01*
G01X43600Y494100D02*
X46100D01*
X45600Y493600D01*
G01X43600D02*
Y494600D01*
G01X46100Y497100D02*
X46017Y496767D01*
X45808Y496517D01*
X45558Y496350D01*
X45225Y496225D01*
X44850Y496183D01*
X44475Y496225D01*
X44142Y496350D01*
X43892Y496517D01*
X43683Y496767D01*
X43600Y497100D01*
X43683Y497433D01*
X43892Y497683D01*
X44142Y497850D01*
X44475Y497975D01*
X44850Y498017D01*
X45225Y497975D01*
X45558Y497850D01*
X45808Y497683D01*
X46017Y497433D01*
X46100Y497100D01*
G01X44642Y499308D02*
X44933Y499600D01*
X45100Y499850D01*
X45183Y500183D01*
X45100Y500475D01*
X44933Y500683D01*
X44683Y500850D01*
X44392Y500892D01*
X44142Y500850D01*
X43892Y500683D01*
X43683Y500433D01*
X43600Y500142D01*
X43683Y499808D01*
X43933Y499517D01*
X44308Y499350D01*
X44725Y499308D01*
X45267Y499392D01*
X45558Y499517D01*
X45850Y499725D01*
X46058Y500017D01*
X46100Y500308D01*
X46017Y500600D01*
X45808Y500808D01*
G01X61533Y509900D02*
Y507400D01*
X59867D01*
G01X58617Y507775D02*
X58367Y507567D01*
X58075Y507442D01*
X57700Y507400D01*
X57325Y507483D01*
X57033Y507650D01*
X56825Y507942D01*
X56783Y508275D01*
X56867Y508608D01*
X57075Y508817D01*
X57367Y508983D01*
X57658Y509025D01*
X57950Y508983D01*
X58325Y508817D01*
X58200Y509900D01*
X57075D01*
G01X55408Y507692D02*
X55117Y507483D01*
X54783Y507400D01*
X54450Y507483D01*
X54158Y507733D01*
X53950Y508108D01*
X53867Y508483D01*
Y508942D01*
X53950Y509317D01*
X54158Y509650D01*
X54408Y509817D01*
X54700Y509900D01*
X55033Y509817D01*
X55283Y509650D01*
X55450Y509400D01*
X55533Y509067D01*
X55450Y508775D01*
X55242Y508483D01*
X54992Y508317D01*
X54700Y508275D01*
X54367Y508358D01*
X54117Y508567D01*
X53867Y508942D01*
G01X79000Y511300D02*
X76500D01*
G01X79000Y510342D02*
Y512258D01*
G01X76500Y513467D02*
X79000D01*
Y514467D01*
X78875Y514800D01*
X78583Y515050D01*
X78250Y515133D01*
X77917Y515050D01*
X77667Y514842D01*
X77542Y514467D01*
Y513467D01*
G01X76500Y517300D02*
X79000D01*
X78500Y516800D01*
G01X76500D02*
Y517800D01*
G01X79000Y520300D02*
X78917Y519967D01*
X78708Y519717D01*
X78458Y519550D01*
X78125Y519425D01*
X77750Y519383D01*
X77375Y519425D01*
X77042Y519550D01*
X76792Y519717D01*
X76583Y519967D01*
X76500Y520300D01*
X76583Y520633D01*
X76792Y520883D01*
X77042Y521050D01*
X77375Y521175D01*
X77750Y521217D01*
X78125Y521175D01*
X78458Y521050D01*
X78708Y520883D01*
X78917Y520633D01*
X79000Y520300D01*
G01X76792Y522592D02*
X76583Y522883D01*
X76500Y523217D01*
X76583Y523550D01*
X76833Y523842D01*
X77208Y524050D01*
X77583Y524133D01*
X78042D01*
X78417Y524050D01*
X78750Y523842D01*
X78917Y523592D01*
X79000Y523300D01*
X78917Y522967D01*
X78750Y522717D01*
X78500Y522550D01*
X78167Y522467D01*
X77875Y522550D01*
X77583Y522758D01*
X77417Y523008D01*
X77375Y523300D01*
X77458Y523633D01*
X77667Y523883D01*
X78042Y524133D01*
G01X75500Y509500D02*
X73000D01*
G01X75500Y508542D02*
Y510458D01*
G01X73000Y511667D02*
X75500D01*
Y512667D01*
X75375Y513000D01*
X75083Y513250D01*
X74750Y513333D01*
X74417Y513250D01*
X74167Y513042D01*
X74042Y512667D01*
Y511667D01*
G01X73000Y515500D02*
X75500D01*
X75000Y515000D01*
G01X73000D02*
Y516000D01*
G01Y518500D02*
X75500D01*
X75000Y518000D01*
G01X73000D02*
Y519000D01*
G01X74042Y520708D02*
X74333Y521000D01*
X74500Y521250D01*
X74583Y521583D01*
X74500Y521875D01*
X74333Y522083D01*
X74083Y522250D01*
X73792Y522292D01*
X73542Y522250D01*
X73292Y522083D01*
X73083Y521833D01*
X73000Y521542D01*
X73083Y521208D01*
X73333Y520917D01*
X73708Y520750D01*
X74125Y520708D01*
X74667Y520792D01*
X74958Y520917D01*
X75250Y521125D01*
X75458Y521417D01*
X75500Y521708D01*
X75417Y522000D01*
X75208Y522208D01*
G01X82731Y490399D02*
Y487899D01*
G01X83689Y490399D02*
X81773D01*
G01X80564Y487899D02*
Y490399D01*
X79564D01*
X79231Y490274D01*
X78981Y489982D01*
X78898Y489649D01*
X78981Y489316D01*
X79189Y489066D01*
X79564Y488941D01*
X80564D01*
G01X76731Y487899D02*
Y490399D01*
X77231Y489899D01*
G01Y487899D02*
X76231D01*
G01X73731D02*
Y490399D01*
X74231Y489899D01*
G01Y487899D02*
X73231D01*
G01X70814D02*
X70731Y488441D01*
X70606Y488899D01*
X70439Y489316D01*
X70231Y489774D01*
X69898Y490399D01*
X71564D01*
G01X36600Y491000D02*
Y488500D01*
G01X37558Y491000D02*
X35642D01*
G01X34433Y488500D02*
Y491000D01*
X33433D01*
X33100Y490875D01*
X32850Y490583D01*
X32767Y490250D01*
X32850Y489917D01*
X33058Y489667D01*
X33433Y489542D01*
X34433D01*
G01X30600Y488500D02*
Y491000D01*
X31100Y490500D01*
G01Y488500D02*
X30100D01*
G01X27600D02*
Y491000D01*
X28100Y490500D01*
G01Y488500D02*
X27100D01*
G01X25308Y488792D02*
X25017Y488583D01*
X24683Y488500D01*
X24350Y488583D01*
X24058Y488833D01*
X23850Y489208D01*
X23767Y489583D01*
Y490042D01*
X23850Y490417D01*
X24058Y490750D01*
X24308Y490917D01*
X24600Y491000D01*
X24933Y490917D01*
X25183Y490750D01*
X25350Y490500D01*
X25433Y490167D01*
X25350Y489875D01*
X25142Y489583D01*
X24892Y489417D01*
X24600Y489375D01*
X24267Y489458D01*
X24017Y489667D01*
X23767Y490042D01*
G01X38133Y507400D02*
Y509900D01*
X37092D01*
X36758Y509775D01*
X36550Y509608D01*
X36467Y509275D01*
X36550Y508942D01*
X36800Y508733D01*
X37092Y508608D01*
X38133D01*
G01X37092D02*
X36467Y507400D01*
G01X35217Y507900D02*
X34967Y507608D01*
X34633Y507442D01*
X34258Y507400D01*
X33925Y507442D01*
X33592Y507650D01*
X33383Y507900D01*
X33342Y508150D01*
X33425Y508442D01*
X33717Y508650D01*
X34008Y508733D01*
X34383D01*
G01X34008D02*
X33758Y508858D01*
X33550Y509067D01*
X33467Y509317D01*
X33550Y509567D01*
X33758Y509775D01*
X34133Y509900D01*
X34508Y509858D01*
X34883Y509692D01*
G01X30800Y507400D02*
Y509900D01*
X32342Y508108D01*
X30258D01*
G01X28300Y507400D02*
Y509900D01*
X28800Y509400D01*
G01Y507400D02*
X27800D01*
G01X62600Y529600D02*
X62933Y529642D01*
X63225Y529808D01*
X63475Y530058D01*
X63642Y530350D01*
X63725Y530683D01*
Y531017D01*
X63642Y531350D01*
X63475Y531642D01*
X63225Y531892D01*
X62933Y532058D01*
X62600Y532100D01*
X62267Y532058D01*
X61975Y531892D01*
X61725Y531642D01*
X61558Y531350D01*
X61475Y531017D01*
Y530683D01*
X61558Y530350D01*
X61725Y530058D01*
X61975Y529808D01*
X62267Y529642D01*
X62600Y529600D01*
G01X62267Y530267D02*
X61767Y529600D01*
G01X60308Y529892D02*
X60017Y529683D01*
X59683Y529600D01*
X59350Y529683D01*
X59058Y529933D01*
X58850Y530308D01*
X58767Y530683D01*
Y531142D01*
X58850Y531517D01*
X59058Y531850D01*
X59308Y532017D01*
X59600Y532100D01*
X59933Y532017D01*
X60183Y531850D01*
X60350Y531600D01*
X60433Y531267D01*
X60350Y530975D01*
X60142Y530683D01*
X59892Y530517D01*
X59600Y530475D01*
X59267Y530558D01*
X59017Y530767D01*
X58767Y531142D01*
G01X48400Y553400D02*
X48733Y553442D01*
X49025Y553608D01*
X49275Y553858D01*
X49442Y554150D01*
X49525Y554483D01*
Y554817D01*
X49442Y555150D01*
X49275Y555442D01*
X49025Y555692D01*
X48733Y555858D01*
X48400Y555900D01*
X48067Y555858D01*
X47775Y555692D01*
X47525Y555442D01*
X47358Y555150D01*
X47275Y554817D01*
Y554483D01*
X47358Y554150D01*
X47525Y553858D01*
X47775Y553608D01*
X48067Y553442D01*
X48400Y553400D01*
G01X48067Y554067D02*
X47567Y553400D01*
G01X45483D02*
X45400Y553942D01*
X45275Y554400D01*
X45108Y554817D01*
X44900Y555275D01*
X44567Y555900D01*
X46233D01*
G01X57251Y611418D02*
X57501Y611543D01*
X57793Y611626D01*
X58126D01*
X58501Y611501D01*
X58793Y611293D01*
X59001Y611043D01*
X59168Y610626D01*
X59210Y610251D01*
X59126Y609876D01*
X59001Y609626D01*
X58751Y609376D01*
X58460Y609209D01*
X58168Y609126D01*
X57876D01*
X57585Y609209D01*
X57335Y609334D01*
X57126Y609501D01*
G01X55168Y609126D02*
Y611626D01*
X55668Y611126D01*
G01Y609126D02*
X54668D01*
G01X52876Y609418D02*
X52585Y609209D01*
X52251Y609126D01*
X51918Y609209D01*
X51626Y609459D01*
X51418Y609834D01*
X51335Y610209D01*
Y610668D01*
X51418Y611043D01*
X51626Y611376D01*
X51876Y611543D01*
X52168Y611626D01*
X52501Y611543D01*
X52751Y611376D01*
X52918Y611126D01*
X53001Y610793D01*
X52918Y610501D01*
X52710Y610209D01*
X52460Y610043D01*
X52168Y610001D01*
X51835Y610084D01*
X51585Y610293D01*
X51335Y610668D01*
G01X48668Y609126D02*
Y611626D01*
X50210Y609834D01*
X48126D01*
G01X57414Y606872D02*
X57664Y606997D01*
X57956Y607080D01*
X58289D01*
X58664Y606955D01*
X58956Y606747D01*
X59164Y606497D01*
X59331Y606080D01*
X59373Y605705D01*
X59289Y605330D01*
X59164Y605080D01*
X58914Y604830D01*
X58623Y604663D01*
X58331Y604580D01*
X58039D01*
X57748Y604663D01*
X57498Y604788D01*
X57289Y604955D01*
G01X55331Y604580D02*
Y607080D01*
X55831Y606580D01*
G01Y604580D02*
X54831D01*
G01X53039Y604872D02*
X52748Y604663D01*
X52414Y604580D01*
X52081Y604663D01*
X51789Y604913D01*
X51581Y605288D01*
X51498Y605663D01*
Y606122D01*
X51581Y606497D01*
X51789Y606830D01*
X52039Y606997D01*
X52331Y607080D01*
X52664Y606997D01*
X52914Y606830D01*
X53081Y606580D01*
X53164Y606247D01*
X53081Y605955D01*
X52873Y605663D01*
X52623Y605497D01*
X52331Y605455D01*
X51998Y605538D01*
X51748Y605747D01*
X51498Y606122D01*
G01X50248Y604955D02*
X49998Y604747D01*
X49706Y604622D01*
X49331Y604580D01*
X48956Y604663D01*
X48664Y604830D01*
X48456Y605122D01*
X48414Y605455D01*
X48498Y605788D01*
X48706Y605997D01*
X48998Y606163D01*
X49289Y606205D01*
X49581Y606163D01*
X49956Y605997D01*
X49831Y607080D01*
X48706D01*
G01X57008Y601839D02*
X57258Y601964D01*
X57550Y602047D01*
X57883D01*
X58258Y601922D01*
X58550Y601714D01*
X58758Y601464D01*
X58925Y601047D01*
X58967Y600672D01*
X58883Y600297D01*
X58758Y600047D01*
X58508Y599797D01*
X58217Y599630D01*
X57925Y599547D01*
X57633D01*
X57342Y599630D01*
X57092Y599755D01*
X56883Y599922D01*
G01X54925Y599547D02*
Y602047D01*
X55425Y601547D01*
G01Y599547D02*
X54425D01*
G01X52633Y599839D02*
X52342Y599630D01*
X52008Y599547D01*
X51675Y599630D01*
X51383Y599880D01*
X51175Y600255D01*
X51092Y600630D01*
Y601089D01*
X51175Y601464D01*
X51383Y601797D01*
X51633Y601964D01*
X51925Y602047D01*
X52258Y601964D01*
X52508Y601797D01*
X52675Y601547D01*
X52758Y601214D01*
X52675Y600922D01*
X52467Y600630D01*
X52217Y600464D01*
X51925Y600422D01*
X51592Y600505D01*
X51342Y600714D01*
X51092Y601089D01*
G01X49717Y600589D02*
X49425Y600880D01*
X49175Y601047D01*
X48842Y601130D01*
X48550Y601047D01*
X48342Y600880D01*
X48175Y600630D01*
X48133Y600339D01*
X48175Y600089D01*
X48342Y599839D01*
X48592Y599630D01*
X48883Y599547D01*
X49217Y599630D01*
X49508Y599880D01*
X49675Y600255D01*
X49717Y600672D01*
X49633Y601214D01*
X49508Y601505D01*
X49300Y601797D01*
X49008Y602005D01*
X48717Y602047D01*
X48425Y601964D01*
X48217Y601755D01*
G01X56845Y597536D02*
X57095Y597661D01*
X57387Y597744D01*
X57720D01*
X58095Y597619D01*
X58387Y597411D01*
X58595Y597161D01*
X58762Y596744D01*
X58804Y596369D01*
X58720Y595994D01*
X58595Y595744D01*
X58345Y595494D01*
X58054Y595327D01*
X57762Y595244D01*
X57470D01*
X57179Y595327D01*
X56929Y595452D01*
X56720Y595619D01*
G01X54762Y595244D02*
Y597744D01*
X55262Y597244D01*
G01Y595244D02*
X54262D01*
G01X52470Y595536D02*
X52179Y595327D01*
X51845Y595244D01*
X51512Y595327D01*
X51220Y595577D01*
X51012Y595952D01*
X50929Y596327D01*
Y596786D01*
X51012Y597161D01*
X51220Y597494D01*
X51470Y597661D01*
X51762Y597744D01*
X52095Y597661D01*
X52345Y597494D01*
X52512Y597244D01*
X52595Y596911D01*
X52512Y596619D01*
X52304Y596327D01*
X52054Y596161D01*
X51762Y596119D01*
X51429Y596202D01*
X51179Y596411D01*
X50929Y596786D01*
G01X48845Y595244D02*
X48762Y595786D01*
X48637Y596244D01*
X48470Y596661D01*
X48262Y597119D01*
X47929Y597744D01*
X49595D01*
G01X56702Y578461D02*
X56952Y578586D01*
X57244Y578669D01*
X57577D01*
X57952Y578544D01*
X58244Y578336D01*
X58452Y578086D01*
X58619Y577669D01*
X58661Y577294D01*
X58577Y576919D01*
X58452Y576669D01*
X58202Y576419D01*
X57911Y576252D01*
X57619Y576169D01*
X57327D01*
X57036Y576252D01*
X56786Y576377D01*
X56577Y576544D01*
G01X54619Y576169D02*
Y578669D01*
X55119Y578169D01*
G01Y576169D02*
X54119D01*
G01X52327Y576461D02*
X52036Y576252D01*
X51702Y576169D01*
X51369Y576252D01*
X51077Y576502D01*
X50869Y576877D01*
X50786Y577252D01*
Y577711D01*
X50869Y578086D01*
X51077Y578419D01*
X51327Y578586D01*
X51619Y578669D01*
X51952Y578586D01*
X52202Y578419D01*
X52369Y578169D01*
X52452Y577836D01*
X52369Y577544D01*
X52161Y577252D01*
X51911Y577086D01*
X51619Y577044D01*
X51286Y577127D01*
X51036Y577336D01*
X50786Y577711D01*
G01X48619Y576169D02*
X48327Y576211D01*
X47994Y576336D01*
X47786Y576544D01*
X47702Y576836D01*
X47786Y577127D01*
X48036Y577377D01*
X48411Y577502D01*
X48827D01*
X49077Y577586D01*
X49286Y577794D01*
X49369Y578086D01*
X49244Y578377D01*
X48952Y578586D01*
X48619Y578669D01*
X48286Y578586D01*
X47994Y578377D01*
X47869Y578086D01*
X47952Y577794D01*
X48161Y577586D01*
X48411Y577502D01*
X48827D01*
X49202Y577377D01*
X49452Y577127D01*
X49536Y576836D01*
X49452Y576544D01*
X49244Y576336D01*
X48911Y576211D01*
X48619Y576169D01*
G01X56790Y574149D02*
X57040Y574274D01*
X57332Y574357D01*
X57665D01*
X58040Y574232D01*
X58332Y574024D01*
X58540Y573774D01*
X58707Y573357D01*
X58749Y572982D01*
X58665Y572607D01*
X58540Y572357D01*
X58290Y572107D01*
X57999Y571940D01*
X57707Y571857D01*
X57415D01*
X57124Y571940D01*
X56874Y572065D01*
X56665Y572232D01*
G01X54707Y571857D02*
Y574357D01*
X55207Y573857D01*
G01Y571857D02*
X54207D01*
G01X52415Y572149D02*
X52124Y571940D01*
X51790Y571857D01*
X51457Y571940D01*
X51165Y572190D01*
X50957Y572565D01*
X50874Y572940D01*
Y573399D01*
X50957Y573774D01*
X51165Y574107D01*
X51415Y574274D01*
X51707Y574357D01*
X52040Y574274D01*
X52290Y574107D01*
X52457Y573857D01*
X52540Y573524D01*
X52457Y573232D01*
X52249Y572940D01*
X51999Y572774D01*
X51707Y572732D01*
X51374Y572815D01*
X51124Y573024D01*
X50874Y573399D01*
G01X49415Y572149D02*
X49124Y571940D01*
X48790Y571857D01*
X48457Y571940D01*
X48165Y572190D01*
X47957Y572565D01*
X47874Y572940D01*
Y573399D01*
X47957Y573774D01*
X48165Y574107D01*
X48415Y574274D01*
X48707Y574357D01*
X49040Y574274D01*
X49290Y574107D01*
X49457Y573857D01*
X49540Y573524D01*
X49457Y573232D01*
X49249Y572940D01*
X48999Y572774D01*
X48707Y572732D01*
X48374Y572815D01*
X48124Y573024D01*
X47874Y573399D01*
G01X56922Y569617D02*
X57172Y569742D01*
X57464Y569825D01*
X57797D01*
X58172Y569700D01*
X58464Y569492D01*
X58672Y569242D01*
X58839Y568825D01*
X58881Y568450D01*
X58797Y568075D01*
X58672Y567825D01*
X58422Y567575D01*
X58131Y567408D01*
X57839Y567325D01*
X57547D01*
X57256Y567408D01*
X57006Y567533D01*
X56797Y567700D01*
G01X55631Y569408D02*
X55381Y569658D01*
X55089Y569783D01*
X54756Y569825D01*
X54339Y569742D01*
X54047Y569533D01*
X53964Y569283D01*
X54006Y569033D01*
X54172Y568825D01*
X55006Y568408D01*
X55381Y568117D01*
X55631Y567700D01*
X55714Y567325D01*
X53964D01*
G01X51839Y569825D02*
X52172Y569742D01*
X52422Y569533D01*
X52589Y569283D01*
X52714Y568950D01*
X52756Y568575D01*
X52714Y568200D01*
X52589Y567867D01*
X52422Y567617D01*
X52172Y567408D01*
X51839Y567325D01*
X51506Y567408D01*
X51256Y567617D01*
X51089Y567867D01*
X50964Y568200D01*
X50922Y568575D01*
X50964Y568950D01*
X51089Y569283D01*
X51256Y569533D01*
X51506Y569742D01*
X51839Y569825D01*
G01X48839D02*
X49172Y569742D01*
X49422Y569533D01*
X49589Y569283D01*
X49714Y568950D01*
X49756Y568575D01*
X49714Y568200D01*
X49589Y567867D01*
X49422Y567617D01*
X49172Y567408D01*
X48839Y567325D01*
X48506Y567408D01*
X48256Y567617D01*
X48089Y567867D01*
X47964Y568200D01*
X47922Y568575D01*
X47964Y568950D01*
X48089Y569283D01*
X48256Y569533D01*
X48506Y569742D01*
X48839Y569825D01*
G01X56570Y564612D02*
X56820Y564737D01*
X57112Y564820D01*
X57445D01*
X57820Y564695D01*
X58112Y564487D01*
X58320Y564237D01*
X58487Y563820D01*
X58529Y563445D01*
X58445Y563070D01*
X58320Y562820D01*
X58070Y562570D01*
X57779Y562403D01*
X57487Y562320D01*
X57195D01*
X56904Y562403D01*
X56654Y562528D01*
X56445Y562695D01*
G01X55279Y564403D02*
X55029Y564653D01*
X54737Y564778D01*
X54404Y564820D01*
X53987Y564737D01*
X53695Y564528D01*
X53612Y564278D01*
X53654Y564028D01*
X53820Y563820D01*
X54654Y563403D01*
X55029Y563112D01*
X55279Y562695D01*
X55362Y562320D01*
X53612D01*
G01X51487Y564820D02*
X51820Y564737D01*
X52070Y564528D01*
X52237Y564278D01*
X52362Y563945D01*
X52404Y563570D01*
X52362Y563195D01*
X52237Y562862D01*
X52070Y562612D01*
X51820Y562403D01*
X51487Y562320D01*
X51154Y562403D01*
X50904Y562612D01*
X50737Y562862D01*
X50612Y563195D01*
X50570Y563570D01*
X50612Y563945D01*
X50737Y564278D01*
X50904Y564528D01*
X51154Y564737D01*
X51487Y564820D01*
G01X48487Y562320D02*
Y564820D01*
X48987Y564320D01*
G01Y562320D02*
X47987D01*
G01X58805Y586662D02*
Y584162D01*
G01X59763Y586662D02*
X57847D01*
G01X56638Y584162D02*
Y586662D01*
X55638D01*
X55305Y586537D01*
X55055Y586245D01*
X54972Y585912D01*
X55055Y585579D01*
X55263Y585329D01*
X55638Y585204D01*
X56638D01*
G01X52805Y584162D02*
Y586662D01*
X53305Y586162D01*
G01Y584162D02*
X52305D01*
G01X50597Y585204D02*
X50305Y585495D01*
X50055Y585662D01*
X49722Y585745D01*
X49430Y585662D01*
X49222Y585495D01*
X49055Y585245D01*
X49013Y584954D01*
X49055Y584704D01*
X49222Y584454D01*
X49472Y584245D01*
X49763Y584162D01*
X50097Y584245D01*
X50388Y584495D01*
X50555Y584870D01*
X50597Y585287D01*
X50513Y585829D01*
X50388Y586120D01*
X50180Y586412D01*
X49888Y586620D01*
X49597Y586662D01*
X49305Y586579D01*
X49097Y586370D01*
G01X46805Y584162D02*
Y586662D01*
X47305Y586162D01*
G01Y584162D02*
X46305D01*
G01X87600Y614600D02*
Y612100D01*
G01X88558Y614600D02*
X86642D01*
G01X85433Y612100D02*
Y614600D01*
X84433D01*
X84100Y614475D01*
X83850Y614183D01*
X83767Y613850D01*
X83850Y613517D01*
X84058Y613267D01*
X84433Y613142D01*
X85433D01*
G01X81600Y612100D02*
Y614600D01*
X82100Y614100D01*
G01Y612100D02*
X81100D01*
G01X79392Y613142D02*
X79100Y613433D01*
X78850Y613600D01*
X78517Y613683D01*
X78225Y613600D01*
X78017Y613433D01*
X77850Y613183D01*
X77808Y612892D01*
X77850Y612642D01*
X78017Y612392D01*
X78267Y612183D01*
X78558Y612100D01*
X78892Y612183D01*
X79183Y612433D01*
X79350Y612808D01*
X79392Y613225D01*
X79308Y613767D01*
X79183Y614058D01*
X78975Y614350D01*
X78683Y614558D01*
X78392Y614600D01*
X78100Y614517D01*
X77892Y614308D01*
G01X75600Y614600D02*
X75933Y614517D01*
X76183Y614308D01*
X76350Y614058D01*
X76475Y613725D01*
X76517Y613350D01*
X76475Y612975D01*
X76350Y612642D01*
X76183Y612392D01*
X75933Y612183D01*
X75600Y612100D01*
X75267Y612183D01*
X75017Y612392D01*
X74850Y612642D01*
X74725Y612975D01*
X74683Y613350D01*
X74725Y613725D01*
X74850Y614058D01*
X75017Y614308D01*
X75267Y614517D01*
X75600Y614600D01*
G01X77700Y585500D02*
Y583000D01*
G01X78658Y585500D02*
X76742D01*
G01X75533Y583000D02*
Y585500D01*
X74533D01*
X74200Y585375D01*
X73950Y585083D01*
X73867Y584750D01*
X73950Y584417D01*
X74158Y584167D01*
X74533Y584042D01*
X75533D01*
G01X71700Y583000D02*
Y585500D01*
X72200Y585000D01*
G01Y583000D02*
X71200D01*
G01X69617Y583375D02*
X69367Y583167D01*
X69075Y583042D01*
X68700Y583000D01*
X68325Y583083D01*
X68033Y583250D01*
X67825Y583542D01*
X67783Y583875D01*
X67867Y584208D01*
X68075Y584417D01*
X68367Y584583D01*
X68658Y584625D01*
X68950Y584583D01*
X69325Y584417D01*
X69200Y585500D01*
X68075D01*
G01X66408Y583292D02*
X66117Y583083D01*
X65783Y583000D01*
X65450Y583083D01*
X65158Y583333D01*
X64950Y583708D01*
X64867Y584083D01*
Y584542D01*
X64950Y584917D01*
X65158Y585250D01*
X65408Y585417D01*
X65700Y585500D01*
X66033Y585417D01*
X66283Y585250D01*
X66450Y585000D01*
X66533Y584667D01*
X66450Y584375D01*
X66242Y584083D01*
X65992Y583917D01*
X65700Y583875D01*
X65367Y583958D01*
X65117Y584167D01*
X64867Y584542D01*
G01X84600Y594500D02*
Y592000D01*
G01X85558Y594500D02*
X83642D01*
G01X82433Y592000D02*
Y594500D01*
X81433D01*
X81100Y594375D01*
X80850Y594083D01*
X80767Y593750D01*
X80850Y593417D01*
X81058Y593167D01*
X81433Y593042D01*
X82433D01*
G01X78600Y592000D02*
Y594500D01*
X79100Y594000D01*
G01Y592000D02*
X78100D01*
G01X76517Y592375D02*
X76267Y592167D01*
X75975Y592042D01*
X75600Y592000D01*
X75225Y592083D01*
X74933Y592250D01*
X74725Y592542D01*
X74683Y592875D01*
X74767Y593208D01*
X74975Y593417D01*
X75267Y593583D01*
X75558Y593625D01*
X75850Y593583D01*
X76225Y593417D01*
X76100Y594500D01*
X74975D01*
G01X72683Y592000D02*
X72600Y592542D01*
X72475Y593000D01*
X72308Y593417D01*
X72100Y593875D01*
X71767Y594500D01*
X73433D01*
G01X85000Y605800D02*
Y603300D01*
G01X85958Y605800D02*
X84042D01*
G01X82833Y603300D02*
Y605800D01*
X81833D01*
X81500Y605675D01*
X81250Y605383D01*
X81167Y605050D01*
X81250Y604717D01*
X81458Y604467D01*
X81833Y604342D01*
X82833D01*
G01X79000Y603300D02*
Y605800D01*
X79500Y605300D01*
G01Y603300D02*
X78500D01*
G01X76917Y603675D02*
X76667Y603467D01*
X76375Y603342D01*
X76000Y603300D01*
X75625Y603383D01*
X75333Y603550D01*
X75125Y603842D01*
X75083Y604175D01*
X75167Y604508D01*
X75375Y604717D01*
X75667Y604883D01*
X75958Y604925D01*
X76250Y604883D01*
X76625Y604717D01*
X76500Y605800D01*
X75375D01*
G01X73917Y603675D02*
X73667Y603467D01*
X73375Y603342D01*
X73000Y603300D01*
X72625Y603383D01*
X72333Y603550D01*
X72125Y603842D01*
X72083Y604175D01*
X72167Y604508D01*
X72375Y604717D01*
X72667Y604883D01*
X72958Y604925D01*
X73250Y604883D01*
X73625Y604717D01*
X73500Y605800D01*
X72375D01*
G01X56845Y695768D02*
X57095Y695893D01*
X57387Y695976D01*
X57720D01*
X58095Y695851D01*
X58387Y695643D01*
X58595Y695393D01*
X58762Y694976D01*
X58804Y694601D01*
X58720Y694226D01*
X58595Y693976D01*
X58345Y693726D01*
X58054Y693559D01*
X57762Y693476D01*
X57470D01*
X57179Y693559D01*
X56929Y693684D01*
X56720Y693851D01*
G01X54762Y693476D02*
Y695976D01*
X55262Y695476D01*
G01Y693476D02*
X54262D01*
G01X52470Y693768D02*
X52179Y693559D01*
X51845Y693476D01*
X51512Y693559D01*
X51220Y693809D01*
X51012Y694184D01*
X50929Y694559D01*
Y695018D01*
X51012Y695393D01*
X51220Y695726D01*
X51470Y695893D01*
X51762Y695976D01*
X52095Y695893D01*
X52345Y695726D01*
X52512Y695476D01*
X52595Y695143D01*
X52512Y694851D01*
X52304Y694559D01*
X52054Y694393D01*
X51762Y694351D01*
X51429Y694434D01*
X51179Y694643D01*
X50929Y695018D01*
G01X48762Y695976D02*
X49095Y695893D01*
X49345Y695684D01*
X49512Y695434D01*
X49637Y695101D01*
X49679Y694726D01*
X49637Y694351D01*
X49512Y694018D01*
X49345Y693768D01*
X49095Y693559D01*
X48762Y693476D01*
X48429Y693559D01*
X48179Y693768D01*
X48012Y694018D01*
X47887Y694351D01*
X47845Y694726D01*
X47887Y695101D01*
X48012Y695434D01*
X48179Y695684D01*
X48429Y695893D01*
X48762Y695976D01*
G01X56926Y691547D02*
X57176Y691672D01*
X57468Y691755D01*
X57801D01*
X58176Y691630D01*
X58468Y691422D01*
X58676Y691172D01*
X58843Y690755D01*
X58885Y690380D01*
X58801Y690005D01*
X58676Y689755D01*
X58426Y689505D01*
X58135Y689338D01*
X57843Y689255D01*
X57551D01*
X57260Y689338D01*
X57010Y689463D01*
X56801Y689630D01*
G01X54843Y689255D02*
Y691755D01*
X55343Y691255D01*
G01Y689255D02*
X54343D01*
G01X52551Y689547D02*
X52260Y689338D01*
X51926Y689255D01*
X51593Y689338D01*
X51301Y689588D01*
X51093Y689963D01*
X51010Y690338D01*
Y690797D01*
X51093Y691172D01*
X51301Y691505D01*
X51551Y691672D01*
X51843Y691755D01*
X52176Y691672D01*
X52426Y691505D01*
X52593Y691255D01*
X52676Y690922D01*
X52593Y690630D01*
X52385Y690338D01*
X52135Y690172D01*
X51843Y690130D01*
X51510Y690213D01*
X51260Y690422D01*
X51010Y690797D01*
G01X48843Y689255D02*
Y691755D01*
X49343Y691255D01*
G01Y689255D02*
X48343D01*
G01X56601Y686513D02*
X56851Y686638D01*
X57143Y686721D01*
X57476D01*
X57851Y686596D01*
X58143Y686388D01*
X58351Y686138D01*
X58518Y685721D01*
X58560Y685346D01*
X58476Y684971D01*
X58351Y684721D01*
X58101Y684471D01*
X57810Y684304D01*
X57518Y684221D01*
X57226D01*
X56935Y684304D01*
X56685Y684429D01*
X56476Y684596D01*
G01X54518Y684221D02*
Y686721D01*
X55018Y686221D01*
G01Y684221D02*
X54018D01*
G01X52226Y684513D02*
X51935Y684304D01*
X51601Y684221D01*
X51268Y684304D01*
X50976Y684554D01*
X50768Y684929D01*
X50685Y685304D01*
Y685763D01*
X50768Y686138D01*
X50976Y686471D01*
X51226Y686638D01*
X51518Y686721D01*
X51851Y686638D01*
X52101Y686471D01*
X52268Y686221D01*
X52351Y685888D01*
X52268Y685596D01*
X52060Y685304D01*
X51810Y685138D01*
X51518Y685096D01*
X51185Y685179D01*
X50935Y685388D01*
X50685Y685763D01*
G01X49310Y686304D02*
X49060Y686554D01*
X48768Y686679D01*
X48435Y686721D01*
X48018Y686638D01*
X47726Y686429D01*
X47643Y686179D01*
X47685Y685929D01*
X47851Y685721D01*
X48685Y685304D01*
X49060Y685013D01*
X49310Y684596D01*
X49393Y684221D01*
X47643D01*
G01X56601Y682535D02*
X56851Y682660D01*
X57143Y682743D01*
X57476D01*
X57851Y682618D01*
X58143Y682410D01*
X58351Y682160D01*
X58518Y681743D01*
X58560Y681368D01*
X58476Y680993D01*
X58351Y680743D01*
X58101Y680493D01*
X57810Y680326D01*
X57518Y680243D01*
X57226D01*
X56935Y680326D01*
X56685Y680451D01*
X56476Y680618D01*
G01X54518Y680243D02*
Y682743D01*
X55018Y682243D01*
G01Y680243D02*
X54018D01*
G01X52226Y680535D02*
X51935Y680326D01*
X51601Y680243D01*
X51268Y680326D01*
X50976Y680576D01*
X50768Y680951D01*
X50685Y681326D01*
Y681785D01*
X50768Y682160D01*
X50976Y682493D01*
X51226Y682660D01*
X51518Y682743D01*
X51851Y682660D01*
X52101Y682493D01*
X52268Y682243D01*
X52351Y681910D01*
X52268Y681618D01*
X52060Y681326D01*
X51810Y681160D01*
X51518Y681118D01*
X51185Y681201D01*
X50935Y681410D01*
X50685Y681785D01*
G01X49435Y680743D02*
X49185Y680451D01*
X48851Y680285D01*
X48476Y680243D01*
X48143Y680285D01*
X47810Y680493D01*
X47601Y680743D01*
X47560Y680993D01*
X47643Y681285D01*
X47935Y681493D01*
X48226Y681576D01*
X48601D01*
G01X48226D02*
X47976Y681701D01*
X47768Y681910D01*
X47685Y682160D01*
X47768Y682410D01*
X47976Y682618D01*
X48351Y682743D01*
X48726Y682701D01*
X49101Y682535D01*
G01X80995Y689234D02*
X78495D01*
G01X80995Y688276D02*
Y690192D01*
G01X78495Y691401D02*
X80995D01*
Y692401D01*
X80870Y692734D01*
X80578Y692984D01*
X80245Y693067D01*
X79912Y692984D01*
X79662Y692776D01*
X79537Y692401D01*
Y691401D01*
G01X78495Y695234D02*
X80995D01*
X80495Y694734D01*
G01X78495D02*
Y695734D01*
G01X78995Y697317D02*
X78703Y697567D01*
X78537Y697901D01*
X78495Y698276D01*
X78537Y698609D01*
X78745Y698942D01*
X78995Y699151D01*
X79245Y699192D01*
X79537Y699109D01*
X79745Y698817D01*
X79828Y698526D01*
Y698151D01*
G01Y698526D02*
X79953Y698776D01*
X80162Y698984D01*
X80412Y699067D01*
X80662Y698984D01*
X80870Y698776D01*
X80995Y698401D01*
X80953Y698026D01*
X80787Y697651D01*
G01X78870Y700317D02*
X78662Y700567D01*
X78537Y700859D01*
X78495Y701234D01*
X78578Y701609D01*
X78745Y701901D01*
X79037Y702109D01*
X79370Y702151D01*
X79703Y702067D01*
X79912Y701859D01*
X80078Y701567D01*
X80120Y701276D01*
X80078Y700984D01*
X79912Y700609D01*
X80995Y700734D01*
Y701859D01*
G01X56926Y729946D02*
X57176Y730071D01*
X57468Y730154D01*
X57801D01*
X58176Y730029D01*
X58468Y729821D01*
X58676Y729571D01*
X58843Y729154D01*
X58885Y728779D01*
X58801Y728404D01*
X58676Y728154D01*
X58426Y727904D01*
X58135Y727737D01*
X57843Y727654D01*
X57551D01*
X57260Y727737D01*
X57010Y727862D01*
X56801Y728029D01*
G01X54843Y727654D02*
Y730154D01*
X55343Y729654D01*
G01Y727654D02*
X54343D01*
G01X51843D02*
X51551Y727696D01*
X51218Y727821D01*
X51010Y728029D01*
X50926Y728321D01*
X51010Y728612D01*
X51260Y728862D01*
X51635Y728987D01*
X52051D01*
X52301Y729071D01*
X52510Y729279D01*
X52593Y729571D01*
X52468Y729862D01*
X52176Y730071D01*
X51843Y730154D01*
X51510Y730071D01*
X51218Y729862D01*
X51093Y729571D01*
X51176Y729279D01*
X51385Y729071D01*
X51635Y728987D01*
X52051D01*
X52426Y728862D01*
X52676Y728612D01*
X52760Y728321D01*
X52676Y728029D01*
X52468Y727821D01*
X52135Y727696D01*
X51843Y727654D01*
G01X49635Y728696D02*
X49343Y728987D01*
X49093Y729154D01*
X48760Y729237D01*
X48468Y729154D01*
X48260Y728987D01*
X48093Y728737D01*
X48051Y728446D01*
X48093Y728196D01*
X48260Y727946D01*
X48510Y727737D01*
X48801Y727654D01*
X49135Y727737D01*
X49426Y727987D01*
X49593Y728362D01*
X49635Y728779D01*
X49551Y729321D01*
X49426Y729612D01*
X49218Y729904D01*
X48926Y730112D01*
X48635Y730154D01*
X48343Y730071D01*
X48135Y729862D01*
G01X57372Y725684D02*
X57622Y725809D01*
X57914Y725892D01*
X58247D01*
X58622Y725767D01*
X58914Y725559D01*
X59122Y725309D01*
X59289Y724892D01*
X59331Y724517D01*
X59247Y724142D01*
X59122Y723892D01*
X58872Y723642D01*
X58581Y723475D01*
X58289Y723392D01*
X57997D01*
X57706Y723475D01*
X57456Y723600D01*
X57247Y723767D01*
G01X55289Y723392D02*
Y725892D01*
X55789Y725392D01*
G01Y723392D02*
X54789D01*
G01X52289D02*
X51997Y723434D01*
X51664Y723559D01*
X51456Y723767D01*
X51372Y724059D01*
X51456Y724350D01*
X51706Y724600D01*
X52081Y724725D01*
X52497D01*
X52747Y724809D01*
X52956Y725017D01*
X53039Y725309D01*
X52914Y725600D01*
X52622Y725809D01*
X52289Y725892D01*
X51956Y725809D01*
X51664Y725600D01*
X51539Y725309D01*
X51622Y725017D01*
X51831Y724809D01*
X52081Y724725D01*
X52497D01*
X52872Y724600D01*
X53122Y724350D01*
X53206Y724059D01*
X53122Y723767D01*
X52914Y723559D01*
X52581Y723434D01*
X52289Y723392D01*
G01X49372D02*
X49289Y723934D01*
X49164Y724392D01*
X48997Y724809D01*
X48789Y725267D01*
X48456Y725892D01*
X50122D01*
G01X56926Y720042D02*
X57176Y720167D01*
X57468Y720250D01*
X57801D01*
X58176Y720125D01*
X58468Y719917D01*
X58676Y719667D01*
X58843Y719250D01*
X58885Y718875D01*
X58801Y718500D01*
X58676Y718250D01*
X58426Y718000D01*
X58135Y717833D01*
X57843Y717750D01*
X57551D01*
X57260Y717833D01*
X57010Y717958D01*
X56801Y718125D01*
G01X54843Y717750D02*
Y720250D01*
X55343Y719750D01*
G01Y717750D02*
X54343D01*
G01X51843D02*
X51551Y717792D01*
X51218Y717917D01*
X51010Y718125D01*
X50926Y718417D01*
X51010Y718708D01*
X51260Y718958D01*
X51635Y719083D01*
X52051D01*
X52301Y719167D01*
X52510Y719375D01*
X52593Y719667D01*
X52468Y719958D01*
X52176Y720167D01*
X51843Y720250D01*
X51510Y720167D01*
X51218Y719958D01*
X51093Y719667D01*
X51176Y719375D01*
X51385Y719167D01*
X51635Y719083D01*
X52051D01*
X52426Y718958D01*
X52676Y718708D01*
X52760Y718417D01*
X52676Y718125D01*
X52468Y717917D01*
X52135Y717792D01*
X51843Y717750D01*
G01X48843D02*
X48551Y717792D01*
X48218Y717917D01*
X48010Y718125D01*
X47926Y718417D01*
X48010Y718708D01*
X48260Y718958D01*
X48635Y719083D01*
X49051D01*
X49301Y719167D01*
X49510Y719375D01*
X49593Y719667D01*
X49468Y719958D01*
X49176Y720167D01*
X48843Y720250D01*
X48510Y720167D01*
X48218Y719958D01*
X48093Y719667D01*
X48176Y719375D01*
X48385Y719167D01*
X48635Y719083D01*
X49051D01*
X49426Y718958D01*
X49676Y718708D01*
X49760Y718417D01*
X49676Y718125D01*
X49468Y717917D01*
X49135Y717792D01*
X48843Y717750D01*
G01X56804Y715739D02*
X57054Y715864D01*
X57346Y715947D01*
X57679D01*
X58054Y715822D01*
X58346Y715614D01*
X58554Y715364D01*
X58721Y714947D01*
X58763Y714572D01*
X58679Y714197D01*
X58554Y713947D01*
X58304Y713697D01*
X58013Y713530D01*
X57721Y713447D01*
X57429D01*
X57138Y713530D01*
X56888Y713655D01*
X56679Y713822D01*
G01X54721Y713447D02*
Y715947D01*
X55221Y715447D01*
G01Y713447D02*
X54221D01*
G01X51721D02*
X51429Y713489D01*
X51096Y713614D01*
X50888Y713822D01*
X50804Y714114D01*
X50888Y714405D01*
X51138Y714655D01*
X51513Y714780D01*
X51929D01*
X52179Y714864D01*
X52388Y715072D01*
X52471Y715364D01*
X52346Y715655D01*
X52054Y715864D01*
X51721Y715947D01*
X51388Y715864D01*
X51096Y715655D01*
X50971Y715364D01*
X51054Y715072D01*
X51263Y714864D01*
X51513Y714780D01*
X51929D01*
X52304Y714655D01*
X52554Y714405D01*
X52638Y714114D01*
X52554Y713822D01*
X52346Y713614D01*
X52013Y713489D01*
X51721Y713447D01*
G01X49429Y713739D02*
X49138Y713530D01*
X48804Y713447D01*
X48471Y713530D01*
X48179Y713780D01*
X47971Y714155D01*
X47888Y714530D01*
Y714989D01*
X47971Y715364D01*
X48179Y715697D01*
X48429Y715864D01*
X48721Y715947D01*
X49054Y715864D01*
X49304Y715697D01*
X49471Y715447D01*
X49554Y715114D01*
X49471Y714822D01*
X49263Y714530D01*
X49013Y714364D01*
X48721Y714322D01*
X48388Y714405D01*
X48138Y714614D01*
X47888Y714989D01*
G01X58374Y705458D02*
Y702958D01*
G01X59332Y705458D02*
X57416D01*
G01X56207Y702958D02*
Y705458D01*
X55207D01*
X54874Y705333D01*
X54624Y705041D01*
X54541Y704708D01*
X54624Y704375D01*
X54832Y704125D01*
X55207Y704000D01*
X56207D01*
G01X52374Y702958D02*
Y705458D01*
X52874Y704958D01*
G01Y702958D02*
X51874D01*
G01X50291Y703458D02*
X50041Y703166D01*
X49707Y703000D01*
X49332Y702958D01*
X48999Y703000D01*
X48666Y703208D01*
X48457Y703458D01*
X48416Y703708D01*
X48499Y704000D01*
X48791Y704208D01*
X49082Y704291D01*
X49457D01*
G01X49082D02*
X48832Y704416D01*
X48624Y704625D01*
X48541Y704875D01*
X48624Y705125D01*
X48832Y705333D01*
X49207Y705458D01*
X49582Y705416D01*
X49957Y705250D01*
G01X46457Y702958D02*
X46374Y703500D01*
X46249Y703958D01*
X46082Y704375D01*
X45874Y704833D01*
X45541Y705458D01*
X47207D01*
G01X75905Y715466D02*
X73405D01*
G01X75905Y714508D02*
Y716424D01*
G01X73405Y717633D02*
X75905D01*
Y718633D01*
X75780Y718966D01*
X75488Y719216D01*
X75155Y719299D01*
X74822Y719216D01*
X74572Y719008D01*
X74447Y718633D01*
Y717633D01*
G01X73405Y721466D02*
X75905D01*
X75405Y720966D01*
G01X73405D02*
Y721966D01*
G01Y724966D02*
X75905D01*
X74113Y723424D01*
Y725508D01*
G01X73405Y727466D02*
X75905D01*
X75405Y726966D01*
G01X73405D02*
Y727966D01*
G01X90007Y182062D02*
Y184562D01*
X88966D01*
X88632Y184437D01*
X88424Y184270D01*
X88341Y183937D01*
X88424Y183604D01*
X88674Y183395D01*
X88966Y183270D01*
X90007D01*
G01X88966D02*
X88341Y182062D01*
G01X87091Y182562D02*
X86841Y182270D01*
X86507Y182104D01*
X86132Y182062D01*
X85799Y182104D01*
X85466Y182312D01*
X85257Y182562D01*
X85216Y182812D01*
X85299Y183104D01*
X85591Y183312D01*
X85882Y183395D01*
X86257D01*
G01X85882D02*
X85632Y183520D01*
X85424Y183729D01*
X85341Y183979D01*
X85424Y184229D01*
X85632Y184437D01*
X86007Y184562D01*
X86382Y184520D01*
X86757Y184354D01*
G01X84091Y182562D02*
X83841Y182270D01*
X83507Y182104D01*
X83132Y182062D01*
X82799Y182104D01*
X82466Y182312D01*
X82257Y182562D01*
X82216Y182812D01*
X82299Y183104D01*
X82591Y183312D01*
X82882Y183395D01*
X83257D01*
G01X82882D02*
X82632Y183520D01*
X82424Y183729D01*
X82341Y183979D01*
X82424Y184229D01*
X82632Y184437D01*
X83007Y184562D01*
X83382Y184520D01*
X83757Y184354D01*
G01X79674Y182062D02*
Y184562D01*
X81216Y182770D01*
X79132D01*
G01X150273Y215155D02*
X150398Y214905D01*
X150481Y214613D01*
Y214280D01*
X150356Y213905D01*
X150148Y213613D01*
X149898Y213405D01*
X149481Y213238D01*
X149106Y213196D01*
X148731Y213280D01*
X148481Y213405D01*
X148231Y213655D01*
X148064Y213946D01*
X147981Y214238D01*
Y214530D01*
X148064Y214821D01*
X148189Y215071D01*
X148356Y215280D01*
G01X147981Y217238D02*
X150481D01*
X149981Y216738D01*
G01X147981D02*
Y217738D01*
G01Y220155D02*
X148523Y220238D01*
X148981Y220363D01*
X149398Y220530D01*
X149856Y220738D01*
X150481Y221071D01*
Y219405D01*
G01X147981Y223155D02*
X148523Y223238D01*
X148981Y223363D01*
X149398Y223530D01*
X149856Y223738D01*
X150481Y224071D01*
Y222405D01*
G01X137780Y216065D02*
X137905Y215815D01*
X137988Y215523D01*
Y215190D01*
X137863Y214815D01*
X137655Y214523D01*
X137405Y214315D01*
X136988Y214148D01*
X136613Y214106D01*
X136238Y214190D01*
X135988Y214315D01*
X135738Y214565D01*
X135571Y214856D01*
X135488Y215148D01*
Y215440D01*
X135571Y215731D01*
X135696Y215981D01*
X135863Y216190D01*
G01X135488Y218148D02*
X137988D01*
X137488Y217648D01*
G01X135488D02*
Y218648D01*
G01Y221065D02*
X136030Y221148D01*
X136488Y221273D01*
X136905Y221440D01*
X137363Y221648D01*
X137988Y221981D01*
Y220315D01*
G01X136530Y223356D02*
X136821Y223648D01*
X136988Y223898D01*
X137071Y224231D01*
X136988Y224523D01*
X136821Y224731D01*
X136571Y224898D01*
X136280Y224940D01*
X136030Y224898D01*
X135780Y224731D01*
X135571Y224481D01*
X135488Y224190D01*
X135571Y223856D01*
X135821Y223565D01*
X136196Y223398D01*
X136613Y223356D01*
X137155Y223440D01*
X137446Y223565D01*
X137738Y223773D01*
X137946Y224065D01*
X137988Y224356D01*
X137905Y224648D01*
X137696Y224856D01*
G01X119192Y216698D02*
X119317Y216448D01*
X119400Y216156D01*
Y215823D01*
X119275Y215448D01*
X119067Y215156D01*
X118817Y214948D01*
X118400Y214781D01*
X118025Y214739D01*
X117650Y214823D01*
X117400Y214948D01*
X117150Y215198D01*
X116983Y215489D01*
X116900Y215781D01*
Y216073D01*
X116983Y216364D01*
X117108Y216614D01*
X117275Y216823D01*
G01X116900Y218781D02*
X119400D01*
X118900Y218281D01*
G01X116900D02*
Y219281D01*
G01Y221698D02*
X117442Y221781D01*
X117900Y221906D01*
X118317Y222073D01*
X118775Y222281D01*
X119400Y222614D01*
Y220948D01*
G01X117275Y223864D02*
X117067Y224114D01*
X116942Y224406D01*
X116900Y224781D01*
X116983Y225156D01*
X117150Y225448D01*
X117442Y225656D01*
X117775Y225698D01*
X118108Y225614D01*
X118317Y225406D01*
X118483Y225114D01*
X118525Y224823D01*
X118483Y224531D01*
X118317Y224156D01*
X119400Y224281D01*
Y225406D01*
G01X108070Y216860D02*
X108195Y216610D01*
X108278Y216318D01*
Y215985D01*
X108153Y215610D01*
X107945Y215318D01*
X107695Y215110D01*
X107278Y214943D01*
X106903Y214901D01*
X106528Y214985D01*
X106278Y215110D01*
X106028Y215360D01*
X105861Y215651D01*
X105778Y215943D01*
Y216235D01*
X105861Y216526D01*
X105986Y216776D01*
X106153Y216985D01*
G01X105778Y218943D02*
X108278D01*
X107778Y218443D01*
G01X105778D02*
Y219443D01*
G01Y221860D02*
X106320Y221943D01*
X106778Y222068D01*
X107195Y222235D01*
X107653Y222443D01*
X108278Y222776D01*
Y221110D01*
G01X105778Y225443D02*
X108278D01*
X106486Y223901D01*
Y225985D01*
G01X96692Y216617D02*
X96817Y216367D01*
X96900Y216075D01*
Y215742D01*
X96775Y215367D01*
X96567Y215075D01*
X96317Y214867D01*
X95900Y214700D01*
X95525Y214658D01*
X95150Y214742D01*
X94900Y214867D01*
X94650Y215117D01*
X94483Y215408D01*
X94400Y215700D01*
Y215992D01*
X94483Y216283D01*
X94608Y216533D01*
X94775Y216742D01*
G01X94400Y218700D02*
X96900D01*
X96400Y218200D01*
G01X94400D02*
Y219200D01*
G01Y221617D02*
X94942Y221700D01*
X95400Y221825D01*
X95817Y221992D01*
X96275Y222200D01*
X96900Y222533D01*
Y220867D01*
G01X94900Y223783D02*
X94608Y224033D01*
X94442Y224367D01*
X94400Y224742D01*
X94442Y225075D01*
X94650Y225408D01*
X94900Y225617D01*
X95150Y225658D01*
X95442Y225575D01*
X95650Y225283D01*
X95733Y224992D01*
Y224617D01*
G01Y224992D02*
X95858Y225242D01*
X96067Y225450D01*
X96317Y225533D01*
X96567Y225450D01*
X96775Y225242D01*
X96900Y224867D01*
X96858Y224492D01*
X96692Y224117D01*
G01X89433Y216400D02*
Y218900D01*
X88392D01*
X88058Y218775D01*
X87850Y218608D01*
X87767Y218275D01*
X87850Y217942D01*
X88100Y217733D01*
X88392Y217608D01*
X89433D01*
G01X88392D02*
X87767Y216400D01*
G01X85683D02*
X85600Y216942D01*
X85475Y217400D01*
X85308Y217817D01*
X85100Y218275D01*
X84767Y218900D01*
X86433D01*
G01X82600Y216400D02*
X82308Y216442D01*
X81975Y216567D01*
X81767Y216775D01*
X81683Y217067D01*
X81767Y217358D01*
X82017Y217608D01*
X82392Y217733D01*
X82808D01*
X83058Y217817D01*
X83267Y218025D01*
X83350Y218317D01*
X83225Y218608D01*
X82933Y218817D01*
X82600Y218900D01*
X82267Y218817D01*
X81975Y218608D01*
X81850Y218317D01*
X81933Y218025D01*
X82142Y217817D01*
X82392Y217733D01*
X82808D01*
X83183Y217608D01*
X83433Y217358D01*
X83517Y217067D01*
X83433Y216775D01*
X83225Y216567D01*
X82892Y216442D01*
X82600Y216400D01*
G01X94383Y312892D02*
X94633Y313017D01*
X94925Y313100D01*
X95258D01*
X95633Y312975D01*
X95925Y312767D01*
X96133Y312517D01*
X96300Y312100D01*
X96342Y311725D01*
X96258Y311350D01*
X96133Y311100D01*
X95883Y310850D01*
X95592Y310683D01*
X95300Y310600D01*
X95008D01*
X94717Y310683D01*
X94467Y310808D01*
X94258Y310975D01*
G01X92300Y310600D02*
Y313100D01*
X92800Y312600D01*
G01Y310600D02*
X91800D01*
G01X89383D02*
X89300Y311142D01*
X89175Y311600D01*
X89008Y312017D01*
X88800Y312475D01*
X88467Y313100D01*
X90133D01*
G01X86300D02*
X86633Y313017D01*
X86883Y312808D01*
X87050Y312558D01*
X87175Y312225D01*
X87217Y311850D01*
X87175Y311475D01*
X87050Y311142D01*
X86883Y310892D01*
X86633Y310683D01*
X86300Y310600D01*
X85967Y310683D01*
X85717Y310892D01*
X85550Y311142D01*
X85425Y311475D01*
X85383Y311850D01*
X85425Y312225D01*
X85550Y312558D01*
X85717Y312808D01*
X85967Y313017D01*
X86300Y313100D01*
G01X106853Y319485D02*
X107103Y319610D01*
X107395Y319693D01*
X107728D01*
X108103Y319568D01*
X108395Y319360D01*
X108603Y319110D01*
X108770Y318693D01*
X108812Y318318D01*
X108728Y317943D01*
X108603Y317693D01*
X108353Y317443D01*
X108062Y317276D01*
X107770Y317193D01*
X107478D01*
X107187Y317276D01*
X106937Y317401D01*
X106728Y317568D01*
G01X104770Y317193D02*
Y319693D01*
X105270Y319193D01*
G01Y317193D02*
X104270D01*
G01X102562Y318235D02*
X102270Y318526D01*
X102020Y318693D01*
X101687Y318776D01*
X101395Y318693D01*
X101187Y318526D01*
X101020Y318276D01*
X100978Y317985D01*
X101020Y317735D01*
X101187Y317485D01*
X101437Y317276D01*
X101728Y317193D01*
X102062Y317276D01*
X102353Y317526D01*
X102520Y317901D01*
X102562Y318318D01*
X102478Y318860D01*
X102353Y319151D01*
X102145Y319443D01*
X101853Y319651D01*
X101562Y319693D01*
X101270Y319610D01*
X101062Y319401D01*
G01X99478Y317485D02*
X99187Y317276D01*
X98853Y317193D01*
X98520Y317276D01*
X98228Y317526D01*
X98020Y317901D01*
X97937Y318276D01*
Y318735D01*
X98020Y319110D01*
X98228Y319443D01*
X98478Y319610D01*
X98770Y319693D01*
X99103Y319610D01*
X99353Y319443D01*
X99520Y319193D01*
X99603Y318860D01*
X99520Y318568D01*
X99312Y318276D01*
X99062Y318110D01*
X98770Y318068D01*
X98437Y318151D01*
X98187Y318360D01*
X97937Y318735D01*
G01X130559Y319566D02*
X130809Y319691D01*
X131101Y319774D01*
X131434D01*
X131809Y319649D01*
X132101Y319441D01*
X132309Y319191D01*
X132476Y318774D01*
X132518Y318399D01*
X132434Y318024D01*
X132309Y317774D01*
X132059Y317524D01*
X131768Y317357D01*
X131476Y317274D01*
X131184D01*
X130893Y317357D01*
X130643Y317482D01*
X130434Y317649D01*
G01X128476Y317274D02*
Y319774D01*
X128976Y319274D01*
G01Y317274D02*
X127976D01*
G01X126268Y318316D02*
X125976Y318607D01*
X125726Y318774D01*
X125393Y318857D01*
X125101Y318774D01*
X124893Y318607D01*
X124726Y318357D01*
X124684Y318066D01*
X124726Y317816D01*
X124893Y317566D01*
X125143Y317357D01*
X125434Y317274D01*
X125768Y317357D01*
X126059Y317607D01*
X126226Y317982D01*
X126268Y318399D01*
X126184Y318941D01*
X126059Y319232D01*
X125851Y319524D01*
X125559Y319732D01*
X125268Y319774D01*
X124976Y319691D01*
X124768Y319482D01*
G01X122476Y317274D02*
X122184Y317316D01*
X121851Y317441D01*
X121643Y317649D01*
X121559Y317941D01*
X121643Y318232D01*
X121893Y318482D01*
X122268Y318607D01*
X122684D01*
X122934Y318691D01*
X123143Y318899D01*
X123226Y319191D01*
X123101Y319482D01*
X122809Y319691D01*
X122476Y319774D01*
X122143Y319691D01*
X121851Y319482D01*
X121726Y319191D01*
X121809Y318899D01*
X122018Y318691D01*
X122268Y318607D01*
X122684D01*
X123059Y318482D01*
X123309Y318232D01*
X123393Y317941D01*
X123309Y317649D01*
X123101Y317441D01*
X122768Y317316D01*
X122476Y317274D01*
G01X136883Y313492D02*
X137133Y313617D01*
X137425Y313700D01*
X137758D01*
X138133Y313575D01*
X138425Y313367D01*
X138633Y313117D01*
X138800Y312700D01*
X138842Y312325D01*
X138758Y311950D01*
X138633Y311700D01*
X138383Y311450D01*
X138092Y311283D01*
X137800Y311200D01*
X137508D01*
X137217Y311283D01*
X136967Y311408D01*
X136758Y311575D01*
G01X134800Y311200D02*
Y313700D01*
X135300Y313200D01*
G01Y311200D02*
X134300D01*
G01X132592Y312242D02*
X132300Y312533D01*
X132050Y312700D01*
X131717Y312783D01*
X131425Y312700D01*
X131217Y312533D01*
X131050Y312283D01*
X131008Y311992D01*
X131050Y311742D01*
X131217Y311492D01*
X131467Y311283D01*
X131758Y311200D01*
X132092Y311283D01*
X132383Y311533D01*
X132550Y311908D01*
X132592Y312325D01*
X132508Y312867D01*
X132383Y313158D01*
X132175Y313450D01*
X131883Y313658D01*
X131592Y313700D01*
X131300Y313617D01*
X131092Y313408D01*
G01X128883Y311200D02*
X128800Y311742D01*
X128675Y312200D01*
X128508Y312617D01*
X128300Y313075D01*
X127967Y313700D01*
X129633D01*
G01X152317Y310879D02*
X152567Y311004D01*
X152859Y311087D01*
X153192D01*
X153567Y310962D01*
X153859Y310754D01*
X154067Y310504D01*
X154234Y310087D01*
X154276Y309712D01*
X154192Y309337D01*
X154067Y309087D01*
X153817Y308837D01*
X153526Y308670D01*
X153234Y308587D01*
X152942D01*
X152651Y308670D01*
X152401Y308795D01*
X152192Y308962D01*
G01X150234Y308587D02*
Y311087D01*
X150734Y310587D01*
G01Y308587D02*
X149734D01*
G01X148026Y309629D02*
X147734Y309920D01*
X147484Y310087D01*
X147151Y310170D01*
X146859Y310087D01*
X146651Y309920D01*
X146484Y309670D01*
X146442Y309379D01*
X146484Y309129D01*
X146651Y308879D01*
X146901Y308670D01*
X147192Y308587D01*
X147526Y308670D01*
X147817Y308920D01*
X147984Y309295D01*
X148026Y309712D01*
X147942Y310254D01*
X147817Y310545D01*
X147609Y310837D01*
X147317Y311045D01*
X147026Y311087D01*
X146734Y311004D01*
X146526Y310795D01*
G01X145026Y309629D02*
X144734Y309920D01*
X144484Y310087D01*
X144151Y310170D01*
X143859Y310087D01*
X143651Y309920D01*
X143484Y309670D01*
X143442Y309379D01*
X143484Y309129D01*
X143651Y308879D01*
X143901Y308670D01*
X144192Y308587D01*
X144526Y308670D01*
X144817Y308920D01*
X144984Y309295D01*
X145026Y309712D01*
X144942Y310254D01*
X144817Y310545D01*
X144609Y310837D01*
X144317Y311045D01*
X144026Y311087D01*
X143734Y311004D01*
X143526Y310795D01*
G01X113884Y321499D02*
X116384D01*
Y322540D01*
X116259Y322874D01*
X116092Y323082D01*
X115759Y323165D01*
X115426Y323082D01*
X115217Y322832D01*
X115092Y322540D01*
Y321499D01*
G01Y322540D02*
X113884Y323165D01*
G01X114176Y324624D02*
X113967Y324915D01*
X113884Y325249D01*
X113967Y325582D01*
X114217Y325874D01*
X114592Y326082D01*
X114967Y326165D01*
X115426D01*
X115801Y326082D01*
X116134Y325874D01*
X116301Y325624D01*
X116384Y325332D01*
X116301Y324999D01*
X116134Y324749D01*
X115884Y324582D01*
X115551Y324499D01*
X115259Y324582D01*
X114967Y324790D01*
X114801Y325040D01*
X114759Y325332D01*
X114842Y325665D01*
X115051Y325915D01*
X115426Y326165D01*
G01X113884Y328832D02*
X116384D01*
X114592Y327290D01*
Y329374D01*
G01X118632Y317111D02*
Y319611D01*
X117591D01*
X117257Y319486D01*
X117049Y319319D01*
X116966Y318986D01*
X117049Y318653D01*
X117299Y318444D01*
X117591Y318319D01*
X118632D01*
G01X117591D02*
X116966Y317111D01*
G01X115507Y317403D02*
X115216Y317194D01*
X114882Y317111D01*
X114549Y317194D01*
X114257Y317444D01*
X114049Y317819D01*
X113966Y318194D01*
Y318653D01*
X114049Y319028D01*
X114257Y319361D01*
X114507Y319528D01*
X114799Y319611D01*
X115132Y319528D01*
X115382Y319361D01*
X115549Y319111D01*
X115632Y318778D01*
X115549Y318486D01*
X115341Y318194D01*
X115091Y318028D01*
X114799Y317986D01*
X114466Y318069D01*
X114216Y318278D01*
X113966Y318653D01*
G01X112716Y317611D02*
X112466Y317319D01*
X112132Y317153D01*
X111757Y317111D01*
X111424Y317153D01*
X111091Y317361D01*
X110882Y317611D01*
X110841Y317861D01*
X110924Y318153D01*
X111216Y318361D01*
X111507Y318444D01*
X111882D01*
G01X111507D02*
X111257Y318569D01*
X111049Y318778D01*
X110966Y319028D01*
X111049Y319278D01*
X111257Y319486D01*
X111632Y319611D01*
X112007Y319569D01*
X112382Y319403D01*
G01X89500Y468000D02*
Y462100D01*
X88600D01*
X88537Y462037D01*
Y443435D01*
X105123D01*
X105100Y428100D01*
X108900D01*
X108898Y416543D01*
X100855D01*
X100500Y416500D01*
Y407600D01*
X107200D01*
Y403500D01*
X121300D01*
Y416800D01*
X139300D01*
X139397Y416905D01*
Y438023D01*
X141597D01*
Y444359D01*
X137374D01*
Y461916D01*
X130567D01*
Y468208D01*
X130500Y468300D01*
X89500D01*
Y468000D01*
G01X106183Y380359D02*
X106433Y380484D01*
X106725Y380567D01*
X107058D01*
X107433Y380442D01*
X107725Y380234D01*
X107933Y379984D01*
X108100Y379567D01*
X108142Y379192D01*
X108058Y378817D01*
X107933Y378567D01*
X107683Y378317D01*
X107392Y378150D01*
X107100Y378067D01*
X106808D01*
X106517Y378150D01*
X106267Y378275D01*
X106058Y378442D01*
G01X104100Y378067D02*
Y380567D01*
X104600Y380067D01*
G01Y378067D02*
X103600D01*
G01X101100D02*
Y380567D01*
X101600Y380067D01*
G01Y378067D02*
X100600D01*
G01X98100D02*
X97808Y378109D01*
X97475Y378234D01*
X97267Y378442D01*
X97183Y378734D01*
X97267Y379025D01*
X97517Y379275D01*
X97892Y379400D01*
X98308D01*
X98558Y379484D01*
X98767Y379692D01*
X98850Y379984D01*
X98725Y380275D01*
X98433Y380484D01*
X98100Y380567D01*
X97767Y380484D01*
X97475Y380275D01*
X97350Y379984D01*
X97433Y379692D01*
X97642Y379484D01*
X97892Y379400D01*
X98308D01*
X98683Y379275D01*
X98933Y379025D01*
X99017Y378734D01*
X98933Y378442D01*
X98725Y378234D01*
X98392Y378109D01*
X98100Y378067D01*
G01X132959Y398117D02*
X133084Y397867D01*
X133167Y397575D01*
Y397242D01*
X133042Y396867D01*
X132834Y396575D01*
X132584Y396367D01*
X132167Y396200D01*
X131792Y396158D01*
X131417Y396242D01*
X131167Y396367D01*
X130917Y396617D01*
X130750Y396908D01*
X130667Y397200D01*
Y397492D01*
X130750Y397783D01*
X130875Y398033D01*
X131042Y398242D01*
G01X130667Y400200D02*
X133167D01*
X132667Y399700D01*
G01X130667D02*
Y400700D01*
G01X131167Y402283D02*
X130875Y402533D01*
X130709Y402867D01*
X130667Y403242D01*
X130709Y403575D01*
X130917Y403908D01*
X131167Y404117D01*
X131417Y404158D01*
X131709Y404075D01*
X131917Y403783D01*
X132000Y403492D01*
Y403117D01*
G01Y403492D02*
X132125Y403742D01*
X132334Y403950D01*
X132584Y404033D01*
X132834Y403950D01*
X133042Y403742D01*
X133167Y403367D01*
X133125Y402992D01*
X132959Y402617D01*
G01X130667Y406117D02*
X131209Y406200D01*
X131667Y406325D01*
X132084Y406492D01*
X132542Y406700D01*
X133167Y407033D01*
Y405367D01*
G01X106183Y375859D02*
X106433Y375984D01*
X106725Y376067D01*
X107058D01*
X107433Y375942D01*
X107725Y375734D01*
X107933Y375484D01*
X108100Y375067D01*
X108142Y374692D01*
X108058Y374317D01*
X107933Y374067D01*
X107683Y373817D01*
X107392Y373650D01*
X107100Y373567D01*
X106808D01*
X106517Y373650D01*
X106267Y373775D01*
X106058Y373942D01*
G01X104100Y373567D02*
Y376067D01*
X104600Y375567D01*
G01Y373567D02*
X103600D01*
G01X101100D02*
Y376067D01*
X101600Y375567D01*
G01Y373567D02*
X100600D01*
G01X98183D02*
X98100Y374109D01*
X97975Y374567D01*
X97808Y374984D01*
X97600Y375442D01*
X97267Y376067D01*
X98933D01*
G01X103000Y397667D02*
X105500D01*
Y398708D01*
X105375Y399042D01*
X105208Y399250D01*
X104875Y399333D01*
X104542Y399250D01*
X104333Y399000D01*
X104208Y398708D01*
Y397667D01*
G01Y398708D02*
X103000Y399333D01*
G01X103500Y400583D02*
X103208Y400833D01*
X103042Y401167D01*
X103000Y401542D01*
X103042Y401875D01*
X103250Y402208D01*
X103500Y402417D01*
X103750Y402458D01*
X104042Y402375D01*
X104250Y402083D01*
X104333Y401792D01*
Y401417D01*
G01Y401792D02*
X104458Y402042D01*
X104667Y402250D01*
X104917Y402333D01*
X105167Y402250D01*
X105375Y402042D01*
X105500Y401667D01*
X105458Y401292D01*
X105292Y400917D01*
G01X105500Y404500D02*
X105417Y404167D01*
X105208Y403917D01*
X104958Y403750D01*
X104625Y403625D01*
X104250Y403583D01*
X103875Y403625D01*
X103542Y403750D01*
X103292Y403917D01*
X103083Y404167D01*
X103000Y404500D01*
X103083Y404833D01*
X103292Y405083D01*
X103542Y405250D01*
X103875Y405375D01*
X104250Y405417D01*
X104625Y405375D01*
X104958Y405250D01*
X105208Y405083D01*
X105417Y404833D01*
X105500Y404500D01*
G01X101266Y382767D02*
X103766D01*
Y383808D01*
X103641Y384142D01*
X103474Y384350D01*
X103141Y384433D01*
X102808Y384350D01*
X102599Y384100D01*
X102474Y383808D01*
Y382767D01*
G01Y383808D02*
X101266Y384433D01*
G01X103349Y385808D02*
X103599Y386058D01*
X103724Y386350D01*
X103766Y386683D01*
X103683Y387100D01*
X103474Y387392D01*
X103224Y387475D01*
X102974Y387433D01*
X102766Y387267D01*
X102349Y386433D01*
X102058Y386058D01*
X101641Y385808D01*
X101266Y385725D01*
Y387475D01*
G01Y389517D02*
X101808Y389600D01*
X102266Y389725D01*
X102683Y389892D01*
X103141Y390100D01*
X103766Y390433D01*
Y388767D01*
G01X105167Y382667D02*
X107667D01*
Y383708D01*
X107542Y384042D01*
X107375Y384250D01*
X107042Y384333D01*
X106709Y384250D01*
X106500Y384000D01*
X106375Y383708D01*
Y382667D01*
G01Y383708D02*
X105167Y384333D01*
G01Y386500D02*
X107667D01*
X107167Y386000D01*
G01X105167D02*
Y387000D01*
G01Y389417D02*
X105709Y389500D01*
X106167Y389625D01*
X106584Y389792D01*
X107042Y390000D01*
X107667Y390333D01*
Y388667D01*
G01X106945Y394185D02*
Y391685D01*
G01X107903Y394185D02*
X105987D01*
G01X104778Y391685D02*
Y394185D01*
X103778D01*
X103445Y394060D01*
X103195Y393768D01*
X103112Y393435D01*
X103195Y393102D01*
X103403Y392852D01*
X103778Y392727D01*
X104778D01*
G01X101653Y391977D02*
X101362Y391768D01*
X101028Y391685D01*
X100695Y391768D01*
X100403Y392018D01*
X100195Y392393D01*
X100112Y392768D01*
Y393227D01*
X100195Y393602D01*
X100403Y393935D01*
X100653Y394102D01*
X100945Y394185D01*
X101278Y394102D01*
X101528Y393935D01*
X101695Y393685D01*
X101778Y393352D01*
X101695Y393060D01*
X101487Y392768D01*
X101237Y392602D01*
X100945Y392560D01*
X100612Y392643D01*
X100362Y392852D01*
X100112Y393227D01*
G01X98862Y392185D02*
X98612Y391893D01*
X98278Y391727D01*
X97903Y391685D01*
X97570Y391727D01*
X97237Y391935D01*
X97028Y392185D01*
X96987Y392435D01*
X97070Y392727D01*
X97362Y392935D01*
X97653Y393018D01*
X98028D01*
G01X97653D02*
X97403Y393143D01*
X97195Y393352D01*
X97112Y393602D01*
X97195Y393852D01*
X97403Y394060D01*
X97778Y394185D01*
X98153Y394143D01*
X98528Y393977D01*
G01X142407Y447962D02*
X144907D01*
Y449003D01*
X144782Y449337D01*
X144615Y449545D01*
X144282Y449628D01*
X143949Y449545D01*
X143740Y449295D01*
X143615Y449003D01*
Y447962D01*
G01Y449003D02*
X142407Y449628D01*
G01X142699Y451087D02*
X142490Y451378D01*
X142407Y451712D01*
X142490Y452045D01*
X142740Y452337D01*
X143115Y452545D01*
X143490Y452628D01*
X143949D01*
X144324Y452545D01*
X144657Y452337D01*
X144824Y452087D01*
X144907Y451795D01*
X144824Y451462D01*
X144657Y451212D01*
X144407Y451045D01*
X144074Y450962D01*
X143782Y451045D01*
X143490Y451253D01*
X143324Y451503D01*
X143282Y451795D01*
X143365Y452128D01*
X143574Y452378D01*
X143949Y452628D01*
G01X121636Y475760D02*
X124136D01*
Y476801D01*
X124011Y477135D01*
X123844Y477343D01*
X123511Y477426D01*
X123178Y477343D01*
X122969Y477093D01*
X122844Y476801D01*
Y475760D01*
G01Y476801D02*
X121636Y477426D01*
G01X123719Y478801D02*
X123969Y479051D01*
X124094Y479343D01*
X124136Y479676D01*
X124053Y480093D01*
X123844Y480385D01*
X123594Y480468D01*
X123344Y480426D01*
X123136Y480260D01*
X122719Y479426D01*
X122428Y479051D01*
X122011Y478801D01*
X121636Y478718D01*
Y480468D01*
G01X122136Y481676D02*
X121844Y481926D01*
X121678Y482260D01*
X121636Y482635D01*
X121678Y482968D01*
X121886Y483301D01*
X122136Y483510D01*
X122386Y483551D01*
X122678Y483468D01*
X122886Y483176D01*
X122969Y482885D01*
Y482510D01*
G01Y482885D02*
X123094Y483135D01*
X123303Y483343D01*
X123553Y483426D01*
X123803Y483343D01*
X124011Y483135D01*
X124136Y482760D01*
X124094Y482385D01*
X123928Y482010D01*
G01X91126Y418606D02*
X93626D01*
Y419647D01*
X93501Y419981D01*
X93334Y420189D01*
X93001Y420272D01*
X92668Y420189D01*
X92459Y419939D01*
X92334Y419647D01*
Y418606D01*
G01Y419647D02*
X91126Y420272D01*
G01Y422439D02*
X93626D01*
X93126Y421939D01*
G01X91126D02*
Y422939D01*
G01Y425439D02*
X91168Y425731D01*
X91293Y426064D01*
X91501Y426272D01*
X91793Y426356D01*
X92084Y426272D01*
X92334Y426022D01*
X92459Y425647D01*
Y425231D01*
X92543Y424981D01*
X92751Y424772D01*
X93043Y424689D01*
X93334Y424814D01*
X93543Y425106D01*
X93626Y425439D01*
X93543Y425772D01*
X93334Y426064D01*
X93043Y426189D01*
X92751Y426106D01*
X92543Y425897D01*
X92459Y425647D01*
Y425231D01*
X92334Y424856D01*
X92084Y424606D01*
X91793Y424522D01*
X91501Y424606D01*
X91293Y424814D01*
X91168Y425147D01*
X91126Y425439D01*
G01X103317Y418548D02*
X100817D01*
G01X103317Y417590D02*
Y419506D01*
G01X100817Y420715D02*
X103317D01*
Y421715D01*
X103192Y422048D01*
X102900Y422298D01*
X102567Y422381D01*
X102234Y422298D01*
X101984Y422090D01*
X101859Y421715D01*
Y420715D01*
G01X101109Y423840D02*
X100900Y424131D01*
X100817Y424465D01*
X100900Y424798D01*
X101150Y425090D01*
X101525Y425298D01*
X101900Y425381D01*
X102359D01*
X102734Y425298D01*
X103067Y425090D01*
X103234Y424840D01*
X103317Y424548D01*
X103234Y424215D01*
X103067Y423965D01*
X102817Y423798D01*
X102484Y423715D01*
X102192Y423798D01*
X101900Y424006D01*
X101734Y424256D01*
X101692Y424548D01*
X101775Y424881D01*
X101984Y425131D01*
X102359Y425381D01*
G01X100817Y428048D02*
X103317D01*
X101525Y426506D01*
Y428590D01*
G01X97688Y440849D02*
Y438349D01*
G01X98646Y440849D02*
X96730D01*
G01X95521Y438349D02*
Y440849D01*
X94521D01*
X94188Y440724D01*
X93938Y440432D01*
X93855Y440099D01*
X93938Y439766D01*
X94146Y439516D01*
X94521Y439391D01*
X95521D01*
G01X91688Y438349D02*
X91396Y438391D01*
X91063Y438516D01*
X90855Y438724D01*
X90771Y439016D01*
X90855Y439307D01*
X91105Y439557D01*
X91480Y439682D01*
X91896D01*
X92146Y439766D01*
X92355Y439974D01*
X92438Y440266D01*
X92313Y440557D01*
X92021Y440766D01*
X91688Y440849D01*
X91355Y440766D01*
X91063Y440557D01*
X90938Y440266D01*
X91021Y439974D01*
X91230Y439766D01*
X91480Y439682D01*
X91896D01*
X92271Y439557D01*
X92521Y439307D01*
X92605Y439016D01*
X92521Y438724D01*
X92313Y438516D01*
X91980Y438391D01*
X91688Y438349D01*
G01X89396Y438641D02*
X89105Y438432D01*
X88771Y438349D01*
X88438Y438432D01*
X88146Y438682D01*
X87938Y439057D01*
X87855Y439432D01*
Y439891D01*
X87938Y440266D01*
X88146Y440599D01*
X88396Y440766D01*
X88688Y440849D01*
X89021Y440766D01*
X89271Y440599D01*
X89438Y440349D01*
X89521Y440016D01*
X89438Y439724D01*
X89230Y439432D01*
X88980Y439266D01*
X88688Y439224D01*
X88355Y439307D01*
X88105Y439516D01*
X87855Y439891D01*
G01X99891Y432807D02*
Y430307D01*
G01X100849Y432807D02*
X98933D01*
G01X97724Y430307D02*
Y432807D01*
X96724D01*
X96391Y432682D01*
X96141Y432390D01*
X96058Y432057D01*
X96141Y431724D01*
X96349Y431474D01*
X96724Y431349D01*
X97724D01*
G01X93891Y430307D02*
Y432807D01*
X94391Y432307D01*
G01Y430307D02*
X93391D01*
G01X90891Y432807D02*
X91224Y432724D01*
X91474Y432515D01*
X91641Y432265D01*
X91766Y431932D01*
X91808Y431557D01*
X91766Y431182D01*
X91641Y430849D01*
X91474Y430599D01*
X91224Y430390D01*
X90891Y430307D01*
X90558Y430390D01*
X90308Y430599D01*
X90141Y430849D01*
X90016Y431182D01*
X89974Y431557D01*
X90016Y431932D01*
X90141Y432265D01*
X90308Y432515D01*
X90558Y432724D01*
X90891Y432807D01*
G01X105347Y480739D02*
X102847D01*
G01X105347Y479781D02*
Y481697D01*
G01X102847Y482906D02*
X105347D01*
Y483906D01*
X105222Y484239D01*
X104930Y484489D01*
X104597Y484572D01*
X104264Y484489D01*
X104014Y484281D01*
X103889Y483906D01*
Y482906D01*
G01X102847Y486739D02*
X105347D01*
X104847Y486239D01*
G01X102847D02*
Y487239D01*
G01X105347Y489739D02*
X105264Y489406D01*
X105055Y489156D01*
X104805Y488989D01*
X104472Y488864D01*
X104097Y488822D01*
X103722Y488864D01*
X103389Y488989D01*
X103139Y489156D01*
X102930Y489406D01*
X102847Y489739D01*
X102930Y490072D01*
X103139Y490322D01*
X103389Y490489D01*
X103722Y490614D01*
X104097Y490656D01*
X104472Y490614D01*
X104805Y490489D01*
X105055Y490322D01*
X105264Y490072D01*
X105347Y489739D01*
G01X102847Y492656D02*
X103389Y492739D01*
X103847Y492864D01*
X104264Y493031D01*
X104722Y493239D01*
X105347Y493572D01*
Y491906D01*
G01X86299Y469810D02*
X83799D01*
G01X86299Y468852D02*
Y470768D01*
G01X83799Y471977D02*
X86299D01*
Y472977D01*
X86174Y473310D01*
X85882Y473560D01*
X85549Y473643D01*
X85216Y473560D01*
X84966Y473352D01*
X84841Y472977D01*
Y471977D01*
G01X83799Y475810D02*
X86299D01*
X85799Y475310D01*
G01X83799D02*
Y476310D01*
G01Y478810D02*
X86299D01*
X85799Y478310D01*
G01X83799D02*
Y479310D01*
G01X86299Y481810D02*
X86216Y481477D01*
X86007Y481227D01*
X85757Y481060D01*
X85424Y480935D01*
X85049Y480893D01*
X84674Y480935D01*
X84341Y481060D01*
X84091Y481227D01*
X83882Y481477D01*
X83799Y481810D01*
X83882Y482143D01*
X84091Y482393D01*
X84341Y482560D01*
X84674Y482685D01*
X85049Y482727D01*
X85424Y482685D01*
X85757Y482560D01*
X86007Y482393D01*
X86216Y482143D01*
X86299Y481810D01*
G01X118933Y483902D02*
X116433D01*
G01X118933Y482944D02*
Y484860D01*
G01X116433Y486069D02*
X118933D01*
Y487069D01*
X118808Y487402D01*
X118516Y487652D01*
X118183Y487735D01*
X117850Y487652D01*
X117600Y487444D01*
X117475Y487069D01*
Y486069D01*
G01X116433Y489902D02*
X118933D01*
X118433Y489402D01*
G01X116433D02*
Y490402D01*
G01Y492902D02*
X118933D01*
X118433Y492402D01*
G01X116433D02*
Y493402D01*
G01Y496402D02*
X118933D01*
X117141Y494860D01*
Y496944D01*
G01X110192Y474304D02*
Y471804D01*
G01X111150Y474304D02*
X109234D01*
G01X108025Y471804D02*
Y474304D01*
X107025D01*
X106692Y474179D01*
X106442Y473887D01*
X106359Y473554D01*
X106442Y473221D01*
X106650Y472971D01*
X107025Y472846D01*
X108025D01*
G01X104192Y471804D02*
Y474304D01*
X104692Y473804D01*
G01Y471804D02*
X103692D01*
G01X101984Y473887D02*
X101734Y474137D01*
X101442Y474262D01*
X101109Y474304D01*
X100692Y474221D01*
X100400Y474012D01*
X100317Y473762D01*
X100359Y473512D01*
X100525Y473304D01*
X101359Y472887D01*
X101734Y472596D01*
X101984Y472179D01*
X102067Y471804D01*
X100317D01*
G01X98192D02*
Y474304D01*
X98692Y473804D01*
G01Y471804D02*
X97692D01*
G01X82287Y465626D02*
X79787D01*
G01X82287Y464668D02*
Y466584D01*
G01X79787Y467793D02*
X82287D01*
Y468793D01*
X82162Y469126D01*
X81870Y469376D01*
X81537Y469459D01*
X81204Y469376D01*
X80954Y469168D01*
X80829Y468793D01*
Y467793D01*
G01X79787Y471626D02*
X82287D01*
X81787Y471126D01*
G01X79787D02*
Y472126D01*
G01X81870Y473834D02*
X82120Y474084D01*
X82245Y474376D01*
X82287Y474709D01*
X82204Y475126D01*
X81995Y475418D01*
X81745Y475501D01*
X81495Y475459D01*
X81287Y475293D01*
X80870Y474459D01*
X80579Y474084D01*
X80162Y473834D01*
X79787Y473751D01*
Y475501D01*
G01X81870Y476834D02*
X82120Y477084D01*
X82245Y477376D01*
X82287Y477709D01*
X82204Y478126D01*
X81995Y478418D01*
X81745Y478501D01*
X81495Y478459D01*
X81287Y478293D01*
X80870Y477459D01*
X80579Y477084D01*
X80162Y476834D01*
X79787Y476751D01*
Y478501D01*
G01X133272Y479131D02*
X130772D01*
G01X133272Y478173D02*
Y480089D01*
G01X130772Y481298D02*
X133272D01*
Y482298D01*
X133147Y482631D01*
X132855Y482881D01*
X132522Y482964D01*
X132189Y482881D01*
X131939Y482673D01*
X131814Y482298D01*
Y481298D01*
G01X130772Y485131D02*
X133272D01*
X132772Y484631D01*
G01X130772D02*
Y485631D01*
G01X131272Y487214D02*
X130980Y487464D01*
X130814Y487798D01*
X130772Y488173D01*
X130814Y488506D01*
X131022Y488839D01*
X131272Y489048D01*
X131522Y489089D01*
X131814Y489006D01*
X132022Y488714D01*
X132105Y488423D01*
Y488048D01*
G01Y488423D02*
X132230Y488673D01*
X132439Y488881D01*
X132689Y488964D01*
X132939Y488881D01*
X133147Y488673D01*
X133272Y488298D01*
X133230Y487923D01*
X133064Y487548D01*
G01X140808Y471565D02*
X138308D01*
G01X140808Y470607D02*
Y472523D01*
G01X138308Y473732D02*
X140808D01*
Y474732D01*
X140683Y475065D01*
X140391Y475315D01*
X140058Y475398D01*
X139725Y475315D01*
X139475Y475107D01*
X139350Y474732D01*
Y473732D01*
G01X138308Y477565D02*
X140808D01*
X140308Y477065D01*
G01X138308D02*
Y478065D01*
G01Y481065D02*
X140808D01*
X139016Y479523D01*
Y481607D01*
G01X157033Y470665D02*
Y468165D01*
G01X157991Y470665D02*
X156075D01*
G01X154866Y468165D02*
Y470665D01*
X153866D01*
X153533Y470540D01*
X153283Y470248D01*
X153200Y469915D01*
X153283Y469582D01*
X153491Y469332D01*
X153866Y469207D01*
X154866D01*
G01X151033Y468165D02*
Y470665D01*
X151533Y470165D01*
G01Y468165D02*
X150533D01*
G01X148950Y468540D02*
X148700Y468332D01*
X148408Y468207D01*
X148033Y468165D01*
X147658Y468248D01*
X147366Y468415D01*
X147158Y468707D01*
X147116Y469040D01*
X147200Y469373D01*
X147408Y469582D01*
X147700Y469748D01*
X147991Y469790D01*
X148283Y469748D01*
X148658Y469582D01*
X148533Y470665D01*
X147408D01*
G01X141163Y455531D02*
X138663D01*
G01X141163Y454573D02*
Y456489D01*
G01X138663Y457698D02*
X141163D01*
Y458698D01*
X141038Y459031D01*
X140746Y459281D01*
X140413Y459364D01*
X140080Y459281D01*
X139830Y459073D01*
X139705Y458698D01*
Y457698D01*
G01X138663Y461531D02*
X141163D01*
X140663Y461031D01*
G01X138663D02*
Y462031D01*
G01Y464531D02*
X138705Y464823D01*
X138830Y465156D01*
X139038Y465364D01*
X139330Y465448D01*
X139621Y465364D01*
X139871Y465114D01*
X139996Y464739D01*
Y464323D01*
X140080Y464073D01*
X140288Y463864D01*
X140580Y463781D01*
X140871Y463906D01*
X141080Y464198D01*
X141163Y464531D01*
X141080Y464864D01*
X140871Y465156D01*
X140580Y465281D01*
X140288Y465198D01*
X140080Y464989D01*
X139996Y464739D01*
Y464323D01*
X139871Y463948D01*
X139621Y463698D01*
X139330Y463614D01*
X139038Y463698D01*
X138830Y463906D01*
X138705Y464239D01*
X138663Y464531D01*
G01X148731Y429236D02*
X146231D01*
G01X148731Y428278D02*
Y430194D01*
G01X146231Y431403D02*
X148731D01*
Y432403D01*
X148606Y432736D01*
X148314Y432986D01*
X147981Y433069D01*
X147648Y432986D01*
X147398Y432778D01*
X147273Y432403D01*
Y431403D01*
G01X148314Y434444D02*
X148564Y434694D01*
X148689Y434986D01*
X148731Y435319D01*
X148648Y435736D01*
X148439Y436028D01*
X148189Y436111D01*
X147939Y436069D01*
X147731Y435903D01*
X147314Y435069D01*
X147023Y434694D01*
X146606Y434444D01*
X146231Y434361D01*
Y436111D01*
G01X147273Y437444D02*
X147564Y437736D01*
X147731Y437986D01*
X147814Y438319D01*
X147731Y438611D01*
X147564Y438819D01*
X147314Y438986D01*
X147023Y439028D01*
X146773Y438986D01*
X146523Y438819D01*
X146314Y438569D01*
X146231Y438278D01*
X146314Y437944D01*
X146564Y437653D01*
X146939Y437486D01*
X147356Y437444D01*
X147898Y437528D01*
X148189Y437653D01*
X148481Y437861D01*
X148689Y438153D01*
X148731Y438444D01*
X148648Y438736D01*
X148439Y438944D01*
G01X144815Y420917D02*
X142315D01*
G01X144815Y419959D02*
Y421875D01*
G01X142315Y423084D02*
X144815D01*
Y424084D01*
X144690Y424417D01*
X144398Y424667D01*
X144065Y424750D01*
X143732Y424667D01*
X143482Y424459D01*
X143357Y424084D01*
Y423084D01*
G01X142815Y426000D02*
X142523Y426250D01*
X142357Y426584D01*
X142315Y426959D01*
X142357Y427292D01*
X142565Y427625D01*
X142815Y427834D01*
X143065Y427875D01*
X143357Y427792D01*
X143565Y427500D01*
X143648Y427209D01*
Y426834D01*
G01Y427209D02*
X143773Y427459D01*
X143982Y427667D01*
X144232Y427750D01*
X144482Y427667D01*
X144690Y427459D01*
X144815Y427084D01*
X144773Y426709D01*
X144607Y426334D01*
G01X142315Y429917D02*
X144815D01*
X144315Y429417D01*
G01X142315D02*
Y430417D01*
G01X144920Y479941D02*
X142420D01*
G01X144920Y478983D02*
Y480899D01*
G01X142420Y482108D02*
X144920D01*
Y483108D01*
X144795Y483441D01*
X144503Y483691D01*
X144170Y483774D01*
X143837Y483691D01*
X143587Y483483D01*
X143462Y483108D01*
Y482108D01*
G01X142795Y485024D02*
X142587Y485274D01*
X142462Y485566D01*
X142420Y485941D01*
X142503Y486316D01*
X142670Y486608D01*
X142962Y486816D01*
X143295Y486858D01*
X143628Y486774D01*
X143837Y486566D01*
X144003Y486274D01*
X144045Y485983D01*
X144003Y485691D01*
X143837Y485316D01*
X144920Y485441D01*
Y486566D01*
G01X143462Y488149D02*
X143753Y488441D01*
X143920Y488691D01*
X144003Y489024D01*
X143920Y489316D01*
X143753Y489524D01*
X143503Y489691D01*
X143212Y489733D01*
X142962Y489691D01*
X142712Y489524D01*
X142503Y489274D01*
X142420Y488983D01*
X142503Y488649D01*
X142753Y488358D01*
X143128Y488191D01*
X143545Y488149D01*
X144087Y488233D01*
X144378Y488358D01*
X144670Y488566D01*
X144878Y488858D01*
X144920Y489149D01*
X144837Y489441D01*
X144628Y489649D01*
G01X111766Y567288D02*
X174903D01*
Y504900D01*
X153200D01*
Y498600D01*
X106619D01*
Y567245D01*
X113219D01*
G01X123633Y543456D02*
X126133D01*
Y544497D01*
X126008Y544831D01*
X125841Y545039D01*
X125508Y545122D01*
X125175Y545039D01*
X124966Y544789D01*
X124841Y544497D01*
Y543456D01*
G01Y544497D02*
X123633Y545122D01*
G01Y547289D02*
X123675Y547581D01*
X123800Y547914D01*
X124008Y548122D01*
X124300Y548206D01*
X124591Y548122D01*
X124841Y547872D01*
X124966Y547497D01*
Y547081D01*
X125050Y546831D01*
X125258Y546622D01*
X125550Y546539D01*
X125841Y546664D01*
X126050Y546956D01*
X126133Y547289D01*
X126050Y547622D01*
X125841Y547914D01*
X125550Y548039D01*
X125258Y547956D01*
X125050Y547747D01*
X124966Y547497D01*
Y547081D01*
X124841Y546706D01*
X124591Y546456D01*
X124300Y546372D01*
X124008Y546456D01*
X123800Y546664D01*
X123675Y546997D01*
X123633Y547289D01*
G01Y550206D02*
X124175Y550289D01*
X124633Y550414D01*
X125050Y550581D01*
X125508Y550789D01*
X126133Y551122D01*
Y549456D01*
G01X119452Y547533D02*
X119702Y547658D01*
X119994Y547741D01*
X120327D01*
X120702Y547616D01*
X120994Y547408D01*
X121202Y547158D01*
X121369Y546741D01*
X121411Y546366D01*
X121327Y545991D01*
X121202Y545741D01*
X120952Y545491D01*
X120661Y545324D01*
X120369Y545241D01*
X120077D01*
X119786Y545324D01*
X119536Y545449D01*
X119327Y545616D01*
G01X117369Y545241D02*
Y547741D01*
X117869Y547241D01*
G01Y545241D02*
X116869D01*
G01X114369Y547741D02*
X114702Y547658D01*
X114952Y547449D01*
X115119Y547199D01*
X115244Y546866D01*
X115286Y546491D01*
X115244Y546116D01*
X115119Y545783D01*
X114952Y545533D01*
X114702Y545324D01*
X114369Y545241D01*
X114036Y545324D01*
X113786Y545533D01*
X113619Y545783D01*
X113494Y546116D01*
X113452Y546491D01*
X113494Y546866D01*
X113619Y547199D01*
X113786Y547449D01*
X114036Y547658D01*
X114369Y547741D01*
G01X111452Y545241D02*
X111369Y545783D01*
X111244Y546241D01*
X111077Y546658D01*
X110869Y547116D01*
X110536Y547741D01*
X112202D01*
G01X146323Y518414D02*
X146573Y518539D01*
X146865Y518622D01*
X147198D01*
X147573Y518497D01*
X147865Y518289D01*
X148073Y518039D01*
X148240Y517622D01*
X148282Y517247D01*
X148198Y516872D01*
X148073Y516622D01*
X147823Y516372D01*
X147532Y516205D01*
X147240Y516122D01*
X146948D01*
X146657Y516205D01*
X146407Y516330D01*
X146198Y516497D01*
G01X144240Y516122D02*
Y518622D01*
X144740Y518122D01*
G01Y516122D02*
X143740D01*
G01X142032Y518205D02*
X141782Y518455D01*
X141490Y518580D01*
X141157Y518622D01*
X140740Y518539D01*
X140448Y518330D01*
X140365Y518080D01*
X140407Y517830D01*
X140573Y517622D01*
X141407Y517205D01*
X141782Y516914D01*
X142032Y516497D01*
X142115Y516122D01*
X140365D01*
G01X139157Y516497D02*
X138907Y516289D01*
X138615Y516164D01*
X138240Y516122D01*
X137865Y516205D01*
X137573Y516372D01*
X137365Y516664D01*
X137323Y516997D01*
X137407Y517330D01*
X137615Y517539D01*
X137907Y517705D01*
X138198Y517747D01*
X138490Y517705D01*
X138865Y517539D01*
X138740Y518622D01*
X137615D01*
G01X129888Y526333D02*
X130138Y526458D01*
X130430Y526541D01*
X130763D01*
X131138Y526416D01*
X131430Y526208D01*
X131638Y525958D01*
X131805Y525541D01*
X131847Y525166D01*
X131763Y524791D01*
X131638Y524541D01*
X131388Y524291D01*
X131097Y524124D01*
X130805Y524041D01*
X130513D01*
X130222Y524124D01*
X129972Y524249D01*
X129763Y524416D01*
G01X127805Y524041D02*
Y526541D01*
X128305Y526041D01*
G01Y524041D02*
X127305D01*
G01X124805Y526541D02*
X125138Y526458D01*
X125388Y526249D01*
X125555Y525999D01*
X125680Y525666D01*
X125722Y525291D01*
X125680Y524916D01*
X125555Y524583D01*
X125388Y524333D01*
X125138Y524124D01*
X124805Y524041D01*
X124472Y524124D01*
X124222Y524333D01*
X124055Y524583D01*
X123930Y524916D01*
X123888Y525291D01*
X123930Y525666D01*
X124055Y525999D01*
X124222Y526249D01*
X124472Y526458D01*
X124805Y526541D01*
G01X121805D02*
X122138Y526458D01*
X122388Y526249D01*
X122555Y525999D01*
X122680Y525666D01*
X122722Y525291D01*
X122680Y524916D01*
X122555Y524583D01*
X122388Y524333D01*
X122138Y524124D01*
X121805Y524041D01*
X121472Y524124D01*
X121222Y524333D01*
X121055Y524583D01*
X120930Y524916D01*
X120888Y525291D01*
X120930Y525666D01*
X121055Y525999D01*
X121222Y526249D01*
X121472Y526458D01*
X121805Y526541D01*
G01X135236Y509086D02*
X135486Y509211D01*
X135778Y509294D01*
X136111D01*
X136486Y509169D01*
X136778Y508961D01*
X136986Y508711D01*
X137153Y508294D01*
X137195Y507919D01*
X137111Y507544D01*
X136986Y507294D01*
X136736Y507044D01*
X136445Y506877D01*
X136153Y506794D01*
X135861D01*
X135570Y506877D01*
X135320Y507002D01*
X135111Y507169D01*
G01X133153Y506794D02*
Y509294D01*
X133653Y508794D01*
G01Y506794D02*
X132653D01*
G01X130153Y509294D02*
X130486Y509211D01*
X130736Y509002D01*
X130903Y508752D01*
X131028Y508419D01*
X131070Y508044D01*
X131028Y507669D01*
X130903Y507336D01*
X130736Y507086D01*
X130486Y506877D01*
X130153Y506794D01*
X129820Y506877D01*
X129570Y507086D01*
X129403Y507336D01*
X129278Y507669D01*
X129236Y508044D01*
X129278Y508419D01*
X129403Y508752D01*
X129570Y509002D01*
X129820Y509211D01*
X130153Y509294D01*
G01X127153Y506794D02*
Y509294D01*
X127653Y508794D01*
G01Y506794D02*
X126653D01*
G01X143239Y536189D02*
X143489Y536314D01*
X143781Y536397D01*
X144114D01*
X144489Y536272D01*
X144781Y536064D01*
X144989Y535814D01*
X145156Y535397D01*
X145198Y535022D01*
X145114Y534647D01*
X144989Y534397D01*
X144739Y534147D01*
X144448Y533980D01*
X144156Y533897D01*
X143864D01*
X143573Y533980D01*
X143323Y534105D01*
X143114Y534272D01*
G01X141864Y534189D02*
X141573Y533980D01*
X141239Y533897D01*
X140906Y533980D01*
X140614Y534230D01*
X140406Y534605D01*
X140323Y534980D01*
Y535439D01*
X140406Y535814D01*
X140614Y536147D01*
X140864Y536314D01*
X141156Y536397D01*
X141489Y536314D01*
X141739Y536147D01*
X141906Y535897D01*
X141989Y535564D01*
X141906Y535272D01*
X141698Y534980D01*
X141448Y534814D01*
X141156Y534772D01*
X140823Y534855D01*
X140573Y535064D01*
X140323Y535439D01*
G01X137656Y533897D02*
Y536397D01*
X139198Y534605D01*
X137114D01*
G01X149575Y542525D02*
X149825Y542650D01*
X150117Y542733D01*
X150450D01*
X150825Y542608D01*
X151117Y542400D01*
X151325Y542150D01*
X151492Y541733D01*
X151534Y541358D01*
X151450Y540983D01*
X151325Y540733D01*
X151075Y540483D01*
X150784Y540316D01*
X150492Y540233D01*
X150200D01*
X149909Y540316D01*
X149659Y540441D01*
X149450Y540608D01*
G01X148200Y540525D02*
X147909Y540316D01*
X147575Y540233D01*
X147242Y540316D01*
X146950Y540566D01*
X146742Y540941D01*
X146659Y541316D01*
Y541775D01*
X146742Y542150D01*
X146950Y542483D01*
X147200Y542650D01*
X147492Y542733D01*
X147825Y542650D01*
X148075Y542483D01*
X148242Y542233D01*
X148325Y541900D01*
X148242Y541608D01*
X148034Y541316D01*
X147784Y541150D01*
X147492Y541108D01*
X147159Y541191D01*
X146909Y541400D01*
X146659Y541775D01*
G01X145409Y540608D02*
X145159Y540400D01*
X144867Y540275D01*
X144492Y540233D01*
X144117Y540316D01*
X143825Y540483D01*
X143617Y540775D01*
X143575Y541108D01*
X143659Y541441D01*
X143867Y541650D01*
X144159Y541816D01*
X144450Y541858D01*
X144742Y541816D01*
X145117Y541650D01*
X144992Y542733D01*
X143867D01*
G01X133384Y536365D02*
X133634Y536490D01*
X133926Y536573D01*
X134259D01*
X134634Y536448D01*
X134926Y536240D01*
X135134Y535990D01*
X135301Y535573D01*
X135343Y535198D01*
X135259Y534823D01*
X135134Y534573D01*
X134884Y534323D01*
X134593Y534156D01*
X134301Y534073D01*
X134009D01*
X133718Y534156D01*
X133468Y534281D01*
X133259Y534448D01*
G01X132009Y534365D02*
X131718Y534156D01*
X131384Y534073D01*
X131051Y534156D01*
X130759Y534406D01*
X130551Y534781D01*
X130468Y535156D01*
Y535615D01*
X130551Y535990D01*
X130759Y536323D01*
X131009Y536490D01*
X131301Y536573D01*
X131634Y536490D01*
X131884Y536323D01*
X132051Y536073D01*
X132134Y535740D01*
X132051Y535448D01*
X131843Y535156D01*
X131593Y534990D01*
X131301Y534948D01*
X130968Y535031D01*
X130718Y535240D01*
X130468Y535615D01*
G01X129093Y535115D02*
X128801Y535406D01*
X128551Y535573D01*
X128218Y535656D01*
X127926Y535573D01*
X127718Y535406D01*
X127551Y535156D01*
X127509Y534865D01*
X127551Y534615D01*
X127718Y534365D01*
X127968Y534156D01*
X128259Y534073D01*
X128593Y534156D01*
X128884Y534406D01*
X129051Y534781D01*
X129093Y535198D01*
X129009Y535740D01*
X128884Y536031D01*
X128676Y536323D01*
X128384Y536531D01*
X128093Y536573D01*
X127801Y536490D01*
X127593Y536281D01*
G01X131272Y531437D02*
X131522Y531562D01*
X131814Y531645D01*
X132147D01*
X132522Y531520D01*
X132814Y531312D01*
X133022Y531062D01*
X133189Y530645D01*
X133231Y530270D01*
X133147Y529895D01*
X133022Y529645D01*
X132772Y529395D01*
X132481Y529228D01*
X132189Y529145D01*
X131897D01*
X131606Y529228D01*
X131356Y529353D01*
X131147Y529520D01*
G01X129897Y529437D02*
X129606Y529228D01*
X129272Y529145D01*
X128939Y529228D01*
X128647Y529478D01*
X128439Y529853D01*
X128356Y530228D01*
Y530687D01*
X128439Y531062D01*
X128647Y531395D01*
X128897Y531562D01*
X129189Y531645D01*
X129522Y531562D01*
X129772Y531395D01*
X129939Y531145D01*
X130022Y530812D01*
X129939Y530520D01*
X129731Y530228D01*
X129481Y530062D01*
X129189Y530020D01*
X128856Y530103D01*
X128606Y530312D01*
X128356Y530687D01*
G01X126272Y529145D02*
X126189Y529687D01*
X126064Y530145D01*
X125897Y530562D01*
X125689Y531020D01*
X125356Y531645D01*
X127022D01*
G01X139457Y542525D02*
X139707Y542650D01*
X139999Y542733D01*
X140332D01*
X140707Y542608D01*
X140999Y542400D01*
X141207Y542150D01*
X141374Y541733D01*
X141416Y541358D01*
X141332Y540983D01*
X141207Y540733D01*
X140957Y540483D01*
X140666Y540316D01*
X140374Y540233D01*
X140082D01*
X139791Y540316D01*
X139541Y540441D01*
X139332Y540608D01*
G01X138082Y540525D02*
X137791Y540316D01*
X137457Y540233D01*
X137124Y540316D01*
X136832Y540566D01*
X136624Y540941D01*
X136541Y541316D01*
Y541775D01*
X136624Y542150D01*
X136832Y542483D01*
X137082Y542650D01*
X137374Y542733D01*
X137707Y542650D01*
X137957Y542483D01*
X138124Y542233D01*
X138207Y541900D01*
X138124Y541608D01*
X137916Y541316D01*
X137666Y541150D01*
X137374Y541108D01*
X137041Y541191D01*
X136791Y541400D01*
X136541Y541775D01*
G01X134374Y540233D02*
X134082Y540275D01*
X133749Y540400D01*
X133541Y540608D01*
X133457Y540900D01*
X133541Y541191D01*
X133791Y541441D01*
X134166Y541566D01*
X134582D01*
X134832Y541650D01*
X135041Y541858D01*
X135124Y542150D01*
X134999Y542441D01*
X134707Y542650D01*
X134374Y542733D01*
X134041Y542650D01*
X133749Y542441D01*
X133624Y542150D01*
X133707Y541858D01*
X133916Y541650D01*
X134166Y541566D01*
X134582D01*
X134957Y541441D01*
X135207Y541191D01*
X135291Y540900D01*
X135207Y540608D01*
X134999Y540400D01*
X134666Y540275D01*
X134374Y540233D01*
G01X156003Y536365D02*
X156253Y536490D01*
X156545Y536573D01*
X156878D01*
X157253Y536448D01*
X157545Y536240D01*
X157753Y535990D01*
X157920Y535573D01*
X157962Y535198D01*
X157878Y534823D01*
X157753Y534573D01*
X157503Y534323D01*
X157212Y534156D01*
X156920Y534073D01*
X156628D01*
X156337Y534156D01*
X156087Y534281D01*
X155878Y534448D01*
G01X153920Y534073D02*
Y536573D01*
X154420Y536073D01*
G01Y534073D02*
X153420D01*
G01X150920D02*
Y536573D01*
X151420Y536073D01*
G01Y534073D02*
X150420D01*
G01X147920D02*
Y536573D01*
X148420Y536073D01*
G01Y534073D02*
X147420D01*
G01X144295Y531261D02*
X144545Y531386D01*
X144837Y531469D01*
X145170D01*
X145545Y531344D01*
X145837Y531136D01*
X146045Y530886D01*
X146212Y530469D01*
X146254Y530094D01*
X146170Y529719D01*
X146045Y529469D01*
X145795Y529219D01*
X145504Y529052D01*
X145212Y528969D01*
X144920D01*
X144629Y529052D01*
X144379Y529177D01*
X144170Y529344D01*
G01X142920Y529261D02*
X142629Y529052D01*
X142295Y528969D01*
X141962Y529052D01*
X141670Y529302D01*
X141462Y529677D01*
X141379Y530052D01*
Y530511D01*
X141462Y530886D01*
X141670Y531219D01*
X141920Y531386D01*
X142212Y531469D01*
X142545Y531386D01*
X142795Y531219D01*
X142962Y530969D01*
X143045Y530636D01*
X142962Y530344D01*
X142754Y530052D01*
X142504Y529886D01*
X142212Y529844D01*
X141879Y529927D01*
X141629Y530136D01*
X141379Y530511D01*
G01X140004Y531052D02*
X139754Y531302D01*
X139462Y531427D01*
X139129Y531469D01*
X138712Y531386D01*
X138420Y531177D01*
X138337Y530927D01*
X138379Y530677D01*
X138545Y530469D01*
X139379Y530052D01*
X139754Y529761D01*
X140004Y529344D01*
X140087Y528969D01*
X138337D01*
G01X140071Y513310D02*
X140321Y513435D01*
X140613Y513518D01*
X140946D01*
X141321Y513393D01*
X141613Y513185D01*
X141821Y512935D01*
X141988Y512518D01*
X142030Y512143D01*
X141946Y511768D01*
X141821Y511518D01*
X141571Y511268D01*
X141280Y511101D01*
X140988Y511018D01*
X140696D01*
X140405Y511101D01*
X140155Y511226D01*
X139946Y511393D01*
G01X137988Y511018D02*
X137696Y511060D01*
X137363Y511185D01*
X137155Y511393D01*
X137071Y511685D01*
X137155Y511976D01*
X137405Y512226D01*
X137780Y512351D01*
X138196D01*
X138446Y512435D01*
X138655Y512643D01*
X138738Y512935D01*
X138613Y513226D01*
X138321Y513435D01*
X137988Y513518D01*
X137655Y513435D01*
X137363Y513226D01*
X137238Y512935D01*
X137321Y512643D01*
X137530Y512435D01*
X137780Y512351D01*
X138196D01*
X138571Y512226D01*
X138821Y511976D01*
X138905Y511685D01*
X138821Y511393D01*
X138613Y511185D01*
X138280Y511060D01*
X137988Y511018D01*
G01X135696Y511310D02*
X135405Y511101D01*
X135071Y511018D01*
X134738Y511101D01*
X134446Y511351D01*
X134238Y511726D01*
X134155Y512101D01*
Y512560D01*
X134238Y512935D01*
X134446Y513268D01*
X134696Y513435D01*
X134988Y513518D01*
X135321Y513435D01*
X135571Y513268D01*
X135738Y513018D01*
X135821Y512685D01*
X135738Y512393D01*
X135530Y512101D01*
X135280Y511935D01*
X134988Y511893D01*
X134655Y511976D01*
X134405Y512185D01*
X134155Y512560D01*
G01X147379Y558012D02*
X147629Y558137D01*
X147921Y558220D01*
X148254D01*
X148629Y558095D01*
X148921Y557887D01*
X149129Y557637D01*
X149296Y557220D01*
X149338Y556845D01*
X149254Y556470D01*
X149129Y556220D01*
X148879Y555970D01*
X148588Y555803D01*
X148296Y555720D01*
X148004D01*
X147713Y555803D01*
X147463Y555928D01*
X147254Y556095D01*
G01X145296Y555720D02*
Y558220D01*
X145796Y557720D01*
G01Y555720D02*
X144796D01*
G01X143088Y557803D02*
X142838Y558053D01*
X142546Y558178D01*
X142213Y558220D01*
X141796Y558137D01*
X141504Y557928D01*
X141421Y557678D01*
X141463Y557428D01*
X141629Y557220D01*
X142463Y556803D01*
X142838Y556512D01*
X143088Y556095D01*
X143171Y555720D01*
X141421D01*
G01X139379D02*
X139296Y556262D01*
X139171Y556720D01*
X139004Y557137D01*
X138796Y557595D01*
X138463Y558220D01*
X140129D01*
G01X147732Y553789D02*
X147982Y553914D01*
X148274Y553997D01*
X148607D01*
X148982Y553872D01*
X149274Y553664D01*
X149482Y553414D01*
X149649Y552997D01*
X149691Y552622D01*
X149607Y552247D01*
X149482Y551997D01*
X149232Y551747D01*
X148941Y551580D01*
X148649Y551497D01*
X148357D01*
X148066Y551580D01*
X147816Y551705D01*
X147607Y551872D01*
G01X145649Y551497D02*
Y553997D01*
X146149Y553497D01*
G01Y551497D02*
X145149D01*
G01X143566Y551997D02*
X143316Y551705D01*
X142982Y551539D01*
X142607Y551497D01*
X142274Y551539D01*
X141941Y551747D01*
X141732Y551997D01*
X141691Y552247D01*
X141774Y552539D01*
X142066Y552747D01*
X142357Y552830D01*
X142732D01*
G01X142357D02*
X142107Y552955D01*
X141899Y553164D01*
X141816Y553414D01*
X141899Y553664D01*
X142107Y553872D01*
X142482Y553997D01*
X142857Y553955D01*
X143232Y553789D01*
G01X140441Y553580D02*
X140191Y553830D01*
X139899Y553955D01*
X139566Y553997D01*
X139149Y553914D01*
X138857Y553705D01*
X138774Y553455D01*
X138816Y553205D01*
X138982Y552997D01*
X139816Y552580D01*
X140191Y552289D01*
X140441Y551872D01*
X140524Y551497D01*
X138774D01*
G01X128357Y539873D02*
X130857D01*
Y540914D01*
X130732Y541248D01*
X130565Y541456D01*
X130232Y541539D01*
X129899Y541456D01*
X129690Y541206D01*
X129565Y540914D01*
Y539873D01*
G01Y540914D02*
X128357Y541539D01*
G01Y543706D02*
X130857D01*
X130357Y543206D01*
G01X128357D02*
Y544206D01*
G01Y547206D02*
X130857D01*
X129065Y545664D01*
Y547748D01*
G01X120736Y554892D02*
X123236D01*
Y555933D01*
X123111Y556267D01*
X122944Y556475D01*
X122611Y556558D01*
X122278Y556475D01*
X122069Y556225D01*
X121944Y555933D01*
Y554892D01*
G01Y555933D02*
X120736Y556558D01*
G01Y558725D02*
X123236D01*
X122736Y558225D01*
G01X120736D02*
Y559225D01*
G01X121778Y560933D02*
X122069Y561225D01*
X122236Y561475D01*
X122319Y561808D01*
X122236Y562100D01*
X122069Y562308D01*
X121819Y562475D01*
X121528Y562517D01*
X121278Y562475D01*
X121028Y562308D01*
X120819Y562058D01*
X120736Y561767D01*
X120819Y561433D01*
X121069Y561142D01*
X121444Y560975D01*
X121861Y560933D01*
X122403Y561017D01*
X122694Y561142D01*
X122986Y561350D01*
X123194Y561642D01*
X123236Y561933D01*
X123153Y562225D01*
X122944Y562433D01*
G01X96300Y487067D02*
X98800D01*
Y488108D01*
X98675Y488442D01*
X98508Y488650D01*
X98175Y488733D01*
X97842Y488650D01*
X97633Y488400D01*
X97508Y488108D01*
Y487067D01*
G01Y488108D02*
X96300Y488733D01*
G01X96800Y489983D02*
X96508Y490233D01*
X96342Y490567D01*
X96300Y490942D01*
X96342Y491275D01*
X96550Y491608D01*
X96800Y491817D01*
X97050Y491858D01*
X97342Y491775D01*
X97550Y491483D01*
X97633Y491192D01*
Y490817D01*
G01Y491192D02*
X97758Y491442D01*
X97967Y491650D01*
X98217Y491733D01*
X98467Y491650D01*
X98675Y491442D01*
X98800Y491067D01*
X98758Y490692D01*
X98592Y490317D01*
G01X96592Y493192D02*
X96383Y493483D01*
X96300Y493817D01*
X96383Y494150D01*
X96633Y494442D01*
X97008Y494650D01*
X97383Y494733D01*
X97842D01*
X98217Y494650D01*
X98550Y494442D01*
X98717Y494192D01*
X98800Y493900D01*
X98717Y493567D01*
X98550Y493317D01*
X98300Y493150D01*
X97967Y493067D01*
X97675Y493150D01*
X97383Y493358D01*
X97217Y493608D01*
X97175Y493900D01*
X97258Y494233D01*
X97467Y494483D01*
X97842Y494733D01*
G01X149259Y501817D02*
X149384Y501567D01*
X149467Y501275D01*
Y500942D01*
X149342Y500567D01*
X149134Y500275D01*
X148884Y500067D01*
X148467Y499900D01*
X148092Y499858D01*
X147717Y499942D01*
X147467Y500067D01*
X147217Y500317D01*
X147050Y500608D01*
X146967Y500900D01*
Y501192D01*
X147050Y501483D01*
X147175Y501733D01*
X147342Y501942D01*
G01X146967Y503900D02*
X149467D01*
X148967Y503400D01*
G01X146967D02*
Y504400D01*
G01X147467Y505983D02*
X147175Y506233D01*
X147009Y506567D01*
X146967Y506942D01*
X147009Y507275D01*
X147217Y507608D01*
X147467Y507817D01*
X147717Y507858D01*
X148009Y507775D01*
X148217Y507483D01*
X148300Y507192D01*
Y506817D01*
G01Y507192D02*
X148425Y507442D01*
X148634Y507650D01*
X148884Y507733D01*
X149134Y507650D01*
X149342Y507442D01*
X149467Y507067D01*
X149425Y506692D01*
X149259Y506317D01*
G01X148009Y509108D02*
X148300Y509400D01*
X148467Y509650D01*
X148550Y509983D01*
X148467Y510275D01*
X148300Y510483D01*
X148050Y510650D01*
X147759Y510692D01*
X147509Y510650D01*
X147259Y510483D01*
X147050Y510233D01*
X146967Y509942D01*
X147050Y509608D01*
X147300Y509317D01*
X147675Y509150D01*
X148092Y509108D01*
X148634Y509192D01*
X148925Y509317D01*
X149217Y509525D01*
X149425Y509817D01*
X149467Y510108D01*
X149384Y510400D01*
X149175Y510608D01*
G01X129417Y556842D02*
X129542Y556592D01*
X129625Y556300D01*
Y555967D01*
X129500Y555592D01*
X129292Y555300D01*
X129042Y555092D01*
X128625Y554925D01*
X128250Y554883D01*
X127875Y554967D01*
X127625Y555092D01*
X127375Y555342D01*
X127208Y555633D01*
X127125Y555925D01*
Y556217D01*
X127208Y556508D01*
X127333Y556758D01*
X127500Y556967D01*
G01X127125Y558925D02*
X129625D01*
X129125Y558425D01*
G01X127125D02*
Y559425D01*
G01X129625Y561925D02*
X129542Y561592D01*
X129333Y561342D01*
X129083Y561175D01*
X128750Y561050D01*
X128375Y561008D01*
X128000Y561050D01*
X127667Y561175D01*
X127417Y561342D01*
X127208Y561592D01*
X127125Y561925D01*
X127208Y562258D01*
X127417Y562508D01*
X127667Y562675D01*
X128000Y562800D01*
X128375Y562842D01*
X128750Y562800D01*
X129083Y562675D01*
X129333Y562508D01*
X129542Y562258D01*
X129625Y561925D01*
G01X127125Y564925D02*
X127167Y565217D01*
X127292Y565550D01*
X127500Y565758D01*
X127792Y565842D01*
X128083Y565758D01*
X128333Y565508D01*
X128458Y565133D01*
Y564717D01*
X128542Y564467D01*
X128750Y564258D01*
X129042Y564175D01*
X129333Y564300D01*
X129542Y564592D01*
X129625Y564925D01*
X129542Y565258D01*
X129333Y565550D01*
X129042Y565675D01*
X128750Y565592D01*
X128542Y565383D01*
X128458Y565133D01*
Y564717D01*
X128333Y564342D01*
X128083Y564092D01*
X127792Y564008D01*
X127500Y564092D01*
X127292Y564300D01*
X127167Y564633D01*
X127125Y564925D01*
G01X135200Y521400D02*
Y518900D01*
G01X136158Y521400D02*
X134242D01*
G01X133033Y518900D02*
Y521400D01*
X132033D01*
X131700Y521275D01*
X131450Y520983D01*
X131367Y520650D01*
X131450Y520317D01*
X131658Y520067D01*
X132033Y519942D01*
X133033D01*
G01X129908Y519192D02*
X129617Y518983D01*
X129283Y518900D01*
X128950Y518983D01*
X128658Y519233D01*
X128450Y519608D01*
X128367Y519983D01*
Y520442D01*
X128450Y520817D01*
X128658Y521150D01*
X128908Y521317D01*
X129200Y521400D01*
X129533Y521317D01*
X129783Y521150D01*
X129950Y520900D01*
X130033Y520567D01*
X129950Y520275D01*
X129742Y519983D01*
X129492Y519817D01*
X129200Y519775D01*
X128867Y519858D01*
X128617Y520067D01*
X128367Y520442D01*
G01X126908Y519192D02*
X126617Y518983D01*
X126283Y518900D01*
X125950Y518983D01*
X125658Y519233D01*
X125450Y519608D01*
X125367Y519983D01*
Y520442D01*
X125450Y520817D01*
X125658Y521150D01*
X125908Y521317D01*
X126200Y521400D01*
X126533Y521317D01*
X126783Y521150D01*
X126950Y520900D01*
X127033Y520567D01*
X126950Y520275D01*
X126742Y519983D01*
X126492Y519817D01*
X126200Y519775D01*
X125867Y519858D01*
X125617Y520067D01*
X125367Y520442D01*
G01X143900Y505100D02*
Y502600D01*
G01X144858Y505100D02*
X142942D01*
G01X141733Y502600D02*
Y505100D01*
X140733D01*
X140400Y504975D01*
X140150Y504683D01*
X140067Y504350D01*
X140150Y504017D01*
X140358Y503767D01*
X140733Y503642D01*
X141733D01*
G01X137900Y502600D02*
Y505100D01*
X138400Y504600D01*
G01Y502600D02*
X137400D01*
G01X134900Y505100D02*
X135233Y505017D01*
X135483Y504808D01*
X135650Y504558D01*
X135775Y504225D01*
X135817Y503850D01*
X135775Y503475D01*
X135650Y503142D01*
X135483Y502892D01*
X135233Y502683D01*
X134900Y502600D01*
X134567Y502683D01*
X134317Y502892D01*
X134150Y503142D01*
X134025Y503475D01*
X133983Y503850D01*
X134025Y504225D01*
X134150Y504558D01*
X134317Y504808D01*
X134567Y505017D01*
X134900Y505100D01*
G01X131900Y502600D02*
Y505100D01*
X132400Y504600D01*
G01Y502600D02*
X131400D01*
G01X83900Y505300D02*
X81400D01*
G01X83900Y504342D02*
Y506258D01*
G01X81400Y507467D02*
X83900D01*
Y508467D01*
X83775Y508800D01*
X83483Y509050D01*
X83150Y509133D01*
X82817Y509050D01*
X82567Y508842D01*
X82442Y508467D01*
Y507467D01*
G01X81400Y511300D02*
X83900D01*
X83400Y510800D01*
G01X81400D02*
Y511800D01*
G01Y514300D02*
X83900D01*
X83400Y513800D01*
G01X81400D02*
Y514800D01*
G01Y517300D02*
X83900D01*
X83400Y516800D01*
G01X81400D02*
Y517800D01*
G01X91709Y502919D02*
X89209D01*
G01X91709Y501961D02*
Y503877D01*
G01X89209Y505086D02*
X91709D01*
Y506086D01*
X91584Y506419D01*
X91292Y506669D01*
X90959Y506752D01*
X90626Y506669D01*
X90376Y506461D01*
X90251Y506086D01*
Y505086D01*
G01X89209Y508919D02*
X91709D01*
X91209Y508419D01*
G01X89209D02*
Y509419D01*
G01Y511919D02*
X91709D01*
X91209Y511419D01*
G01X89209D02*
Y512419D01*
G01X89709Y514002D02*
X89417Y514252D01*
X89251Y514586D01*
X89209Y514961D01*
X89251Y515294D01*
X89459Y515627D01*
X89709Y515836D01*
X89959Y515877D01*
X90251Y515794D01*
X90459Y515502D01*
X90542Y515211D01*
Y514836D01*
G01Y515211D02*
X90667Y515461D01*
X90876Y515669D01*
X91126Y515752D01*
X91376Y515669D01*
X91584Y515461D01*
X91709Y515086D01*
X91667Y514711D01*
X91501Y514336D01*
G01X100200Y500100D02*
X97700D01*
G01X100200Y499142D02*
Y501058D01*
G01X97700Y502267D02*
X100200D01*
Y503267D01*
X100075Y503600D01*
X99783Y503850D01*
X99450Y503933D01*
X99117Y503850D01*
X98867Y503642D01*
X98742Y503267D01*
Y502267D01*
G01X97700Y506100D02*
X100200D01*
X99700Y505600D01*
G01X97700D02*
Y506600D01*
G01X99783Y508308D02*
X100033Y508558D01*
X100158Y508850D01*
X100200Y509183D01*
X100117Y509600D01*
X99908Y509892D01*
X99658Y509975D01*
X99408Y509933D01*
X99200Y509767D01*
X98783Y508933D01*
X98492Y508558D01*
X98075Y508308D01*
X97700Y508225D01*
Y509975D01*
G01X98200Y511183D02*
X97908Y511433D01*
X97742Y511767D01*
X97700Y512142D01*
X97742Y512475D01*
X97950Y512808D01*
X98200Y513017D01*
X98450Y513058D01*
X98742Y512975D01*
X98950Y512683D01*
X99033Y512392D01*
Y512017D01*
G01Y512392D02*
X99158Y512642D01*
X99367Y512850D01*
X99617Y512933D01*
X99867Y512850D01*
X100075Y512642D01*
X100200Y512267D01*
X100158Y511892D01*
X99992Y511517D01*
G01X95600Y506200D02*
X93100D01*
G01X95600Y505242D02*
Y507158D01*
G01X93100Y508367D02*
X95600D01*
Y509367D01*
X95475Y509700D01*
X95183Y509950D01*
X94850Y510033D01*
X94517Y509950D01*
X94267Y509742D01*
X94142Y509367D01*
Y508367D01*
G01X93100Y512200D02*
X95600D01*
X95100Y511700D01*
G01X93100D02*
Y512700D01*
G01X95183Y514408D02*
X95433Y514658D01*
X95558Y514950D01*
X95600Y515283D01*
X95517Y515700D01*
X95308Y515992D01*
X95058Y516075D01*
X94808Y516033D01*
X94600Y515867D01*
X94183Y515033D01*
X93892Y514658D01*
X93475Y514408D01*
X93100Y514325D01*
Y516075D01*
G01Y518700D02*
X95600D01*
X93808Y517158D01*
Y519242D01*
G01X87900Y511400D02*
X85400D01*
G01X87900Y510442D02*
Y512358D01*
G01X85400Y513567D02*
X87900D01*
Y514567D01*
X87775Y514900D01*
X87483Y515150D01*
X87150Y515233D01*
X86817Y515150D01*
X86567Y514942D01*
X86442Y514567D01*
Y513567D01*
G01X85400Y517400D02*
X87900D01*
X87400Y516900D01*
G01X85400D02*
Y517900D01*
G01X87483Y519608D02*
X87733Y519858D01*
X87858Y520150D01*
X87900Y520483D01*
X87817Y520900D01*
X87608Y521192D01*
X87358Y521275D01*
X87108Y521233D01*
X86900Y521067D01*
X86483Y520233D01*
X86192Y519858D01*
X85775Y519608D01*
X85400Y519525D01*
Y521275D01*
G01X85775Y522483D02*
X85567Y522733D01*
X85442Y523025D01*
X85400Y523400D01*
X85483Y523775D01*
X85650Y524067D01*
X85942Y524275D01*
X86275Y524317D01*
X86608Y524233D01*
X86817Y524025D01*
X86983Y523733D01*
X87025Y523442D01*
X86983Y523150D01*
X86817Y522775D01*
X87900Y522900D01*
Y524025D01*
G01X135763Y552974D02*
Y550474D01*
G01X136721Y552974D02*
X134805D01*
G01X133596Y550474D02*
Y552974D01*
X132596D01*
X132263Y552849D01*
X132013Y552557D01*
X131930Y552224D01*
X132013Y551891D01*
X132221Y551641D01*
X132596Y551516D01*
X133596D01*
G01X129846Y550474D02*
X129763Y551016D01*
X129638Y551474D01*
X129471Y551891D01*
X129263Y552349D01*
X128930Y552974D01*
X130596D01*
G01X145175Y562060D02*
X145425Y562185D01*
X145717Y562268D01*
X146050D01*
X146425Y562143D01*
X146717Y561935D01*
X146925Y561685D01*
X147092Y561268D01*
X147134Y560893D01*
X147050Y560518D01*
X146925Y560268D01*
X146675Y560018D01*
X146384Y559851D01*
X146092Y559768D01*
X145800D01*
X145509Y559851D01*
X145259Y559976D01*
X145050Y560143D01*
G01X143800Y560060D02*
X143509Y559851D01*
X143175Y559768D01*
X142842Y559851D01*
X142550Y560101D01*
X142342Y560476D01*
X142259Y560851D01*
Y561310D01*
X142342Y561685D01*
X142550Y562018D01*
X142800Y562185D01*
X143092Y562268D01*
X143425Y562185D01*
X143675Y562018D01*
X143842Y561768D01*
X143925Y561435D01*
X143842Y561143D01*
X143634Y560851D01*
X143384Y560685D01*
X143092Y560643D01*
X142759Y560726D01*
X142509Y560935D01*
X142259Y561310D01*
G01X140800Y560060D02*
X140509Y559851D01*
X140175Y559768D01*
X139842Y559851D01*
X139550Y560101D01*
X139342Y560476D01*
X139259Y560851D01*
Y561310D01*
X139342Y561685D01*
X139550Y562018D01*
X139800Y562185D01*
X140092Y562268D01*
X140425Y562185D01*
X140675Y562018D01*
X140842Y561768D01*
X140925Y561435D01*
X140842Y561143D01*
X140634Y560851D01*
X140384Y560685D01*
X140092Y560643D01*
X139759Y560726D01*
X139509Y560935D01*
X139259Y561310D01*
G01X101200Y579700D02*
Y577200D01*
G01X102158Y579700D02*
X100242D01*
G01X99033Y577200D02*
Y579700D01*
X98033D01*
X97700Y579575D01*
X97450Y579283D01*
X97367Y578950D01*
X97450Y578617D01*
X97658Y578367D01*
X98033Y578242D01*
X99033D01*
G01X95200Y577200D02*
Y579700D01*
X95700Y579200D01*
G01Y577200D02*
X94700D01*
G01X93117Y577575D02*
X92867Y577367D01*
X92575Y577242D01*
X92200Y577200D01*
X91825Y577283D01*
X91533Y577450D01*
X91325Y577742D01*
X91283Y578075D01*
X91367Y578408D01*
X91575Y578617D01*
X91867Y578783D01*
X92158Y578825D01*
X92450Y578783D01*
X92825Y578617D01*
X92700Y579700D01*
X91575D01*
G01X89200Y577200D02*
X88908Y577242D01*
X88575Y577367D01*
X88367Y577575D01*
X88283Y577867D01*
X88367Y578158D01*
X88617Y578408D01*
X88992Y578533D01*
X89408D01*
X89658Y578617D01*
X89867Y578825D01*
X89950Y579117D01*
X89825Y579408D01*
X89533Y579617D01*
X89200Y579700D01*
X88867Y579617D01*
X88575Y579408D01*
X88450Y579117D01*
X88533Y578825D01*
X88742Y578617D01*
X88992Y578533D01*
X89408D01*
X89783Y578408D01*
X90033Y578158D01*
X90117Y577867D01*
X90033Y577575D01*
X89825Y577367D01*
X89492Y577242D01*
X89200Y577200D01*
G01X112800Y594400D02*
Y591900D01*
G01X113758Y594400D02*
X111842D01*
G01X110633Y591900D02*
Y594400D01*
X109633D01*
X109300Y594275D01*
X109050Y593983D01*
X108967Y593650D01*
X109050Y593317D01*
X109258Y593067D01*
X109633Y592942D01*
X110633D01*
G01X106800Y591900D02*
Y594400D01*
X107300Y593900D01*
G01Y591900D02*
X106300D01*
G01X104717Y592275D02*
X104467Y592067D01*
X104175Y591942D01*
X103800Y591900D01*
X103425Y591983D01*
X103133Y592150D01*
X102925Y592442D01*
X102883Y592775D01*
X102967Y593108D01*
X103175Y593317D01*
X103467Y593483D01*
X103758Y593525D01*
X104050Y593483D01*
X104425Y593317D01*
X104300Y594400D01*
X103175D01*
G01X101592Y592942D02*
X101300Y593233D01*
X101050Y593400D01*
X100717Y593483D01*
X100425Y593400D01*
X100217Y593233D01*
X100050Y592983D01*
X100008Y592692D01*
X100050Y592442D01*
X100217Y592192D01*
X100467Y591983D01*
X100758Y591900D01*
X101092Y591983D01*
X101383Y592233D01*
X101550Y592608D01*
X101592Y593025D01*
X101508Y593567D01*
X101383Y593858D01*
X101175Y594150D01*
X100883Y594358D01*
X100592Y594400D01*
X100300Y594317D01*
X100092Y594108D01*
G01X98200Y601900D02*
Y599400D01*
G01X99158Y601900D02*
X97242D01*
G01X96033Y599400D02*
Y601900D01*
X95033D01*
X94700Y601775D01*
X94450Y601483D01*
X94367Y601150D01*
X94450Y600817D01*
X94658Y600567D01*
X95033Y600442D01*
X96033D01*
G01X92200Y599400D02*
Y601900D01*
X92700Y601400D01*
G01Y599400D02*
X91700D01*
G01X90117Y599775D02*
X89867Y599567D01*
X89575Y599442D01*
X89200Y599400D01*
X88825Y599483D01*
X88533Y599650D01*
X88325Y599942D01*
X88283Y600275D01*
X88367Y600608D01*
X88575Y600817D01*
X88867Y600983D01*
X89158Y601025D01*
X89450Y600983D01*
X89825Y600817D01*
X89700Y601900D01*
X88575D01*
G01X85700Y599400D02*
Y601900D01*
X87242Y600108D01*
X85158D01*
G01X100755Y683834D02*
X98255D01*
G01X100755Y682876D02*
Y684792D01*
G01X98255Y686001D02*
X100755D01*
Y687001D01*
X100630Y687334D01*
X100338Y687584D01*
X100005Y687667D01*
X99672Y687584D01*
X99422Y687376D01*
X99297Y687001D01*
Y686001D01*
G01X98255Y689834D02*
X100755D01*
X100255Y689334D01*
G01X98255D02*
Y690334D01*
G01X98755Y691917D02*
X98463Y692167D01*
X98297Y692501D01*
X98255Y692876D01*
X98297Y693209D01*
X98505Y693542D01*
X98755Y693751D01*
X99005Y693792D01*
X99297Y693709D01*
X99505Y693417D01*
X99588Y693126D01*
Y692751D01*
G01Y693126D02*
X99713Y693376D01*
X99922Y693584D01*
X100172Y693667D01*
X100422Y693584D01*
X100630Y693376D01*
X100755Y693001D01*
X100713Y692626D01*
X100547Y692251D01*
G01X98547Y695126D02*
X98338Y695417D01*
X98255Y695751D01*
X98338Y696084D01*
X98588Y696376D01*
X98963Y696584D01*
X99338Y696667D01*
X99797D01*
X100172Y696584D01*
X100505Y696376D01*
X100672Y696126D01*
X100755Y695834D01*
X100672Y695501D01*
X100505Y695251D01*
X100255Y695084D01*
X99922Y695001D01*
X99630Y695084D01*
X99338Y695292D01*
X99172Y695542D01*
X99130Y695834D01*
X99213Y696167D01*
X99422Y696417D01*
X99797Y696667D01*
G01X114256Y717704D02*
Y715204D01*
G01X115214Y717704D02*
X113298D01*
G01X112089Y715204D02*
Y717704D01*
X111089D01*
X110756Y717579D01*
X110506Y717287D01*
X110423Y716954D01*
X110506Y716621D01*
X110714Y716371D01*
X111089Y716246D01*
X112089D01*
G01X108256Y715204D02*
Y717704D01*
X108756Y717204D01*
G01Y715204D02*
X107756D01*
G01X106173Y715704D02*
X105923Y715412D01*
X105589Y715246D01*
X105214Y715204D01*
X104881Y715246D01*
X104548Y715454D01*
X104339Y715704D01*
X104298Y715954D01*
X104381Y716246D01*
X104673Y716454D01*
X104964Y716537D01*
X105339D01*
G01X104964D02*
X104714Y716662D01*
X104506Y716871D01*
X104423Y717121D01*
X104506Y717371D01*
X104714Y717579D01*
X105089Y717704D01*
X105464Y717662D01*
X105839Y717496D01*
G01X101756Y715204D02*
Y717704D01*
X103298Y715912D01*
X101214D01*
G01X113939Y712158D02*
Y709658D01*
G01X114897Y712158D02*
X112981D01*
G01X111772Y709658D02*
Y712158D01*
X110772D01*
X110439Y712033D01*
X110189Y711741D01*
X110106Y711408D01*
X110189Y711075D01*
X110397Y710825D01*
X110772Y710700D01*
X111772D01*
G01X107939Y709658D02*
Y712158D01*
X108439Y711658D01*
G01Y709658D02*
X107439D01*
G01X105856Y710158D02*
X105606Y709866D01*
X105272Y709700D01*
X104897Y709658D01*
X104564Y709700D01*
X104231Y709908D01*
X104022Y710158D01*
X103981Y710408D01*
X104064Y710700D01*
X104356Y710908D01*
X104647Y710991D01*
X105022D01*
G01X104647D02*
X104397Y711116D01*
X104189Y711325D01*
X104106Y711575D01*
X104189Y711825D01*
X104397Y712033D01*
X104772Y712158D01*
X105147Y712116D01*
X105522Y711950D01*
G01X102731Y710700D02*
X102439Y710991D01*
X102189Y711158D01*
X101856Y711241D01*
X101564Y711158D01*
X101356Y710991D01*
X101189Y710741D01*
X101147Y710450D01*
X101189Y710200D01*
X101356Y709950D01*
X101606Y709741D01*
X101897Y709658D01*
X102231Y709741D01*
X102522Y709991D01*
X102689Y710366D01*
X102731Y710783D01*
X102647Y711325D01*
X102522Y711616D01*
X102314Y711908D01*
X102022Y712116D01*
X101731Y712158D01*
X101439Y712075D01*
X101231Y711866D01*
G01X124280Y705087D02*
Y702587D01*
G01X125238Y705087D02*
X123322D01*
G01X122113Y702587D02*
Y705087D01*
X121113D01*
X120780Y704962D01*
X120530Y704670D01*
X120447Y704337D01*
X120530Y704004D01*
X120738Y703754D01*
X121113Y703629D01*
X122113D01*
G01X118280Y702587D02*
Y705087D01*
X118780Y704587D01*
G01Y702587D02*
X117780D01*
G01X116197Y703087D02*
X115947Y702795D01*
X115613Y702629D01*
X115238Y702587D01*
X114905Y702629D01*
X114572Y702837D01*
X114363Y703087D01*
X114322Y703337D01*
X114405Y703629D01*
X114697Y703837D01*
X114988Y703920D01*
X115363D01*
G01X114988D02*
X114738Y704045D01*
X114530Y704254D01*
X114447Y704504D01*
X114530Y704754D01*
X114738Y704962D01*
X115113Y705087D01*
X115488Y705045D01*
X115863Y704879D01*
G01X112280Y702587D02*
X111988Y702629D01*
X111655Y702754D01*
X111447Y702962D01*
X111363Y703254D01*
X111447Y703545D01*
X111697Y703795D01*
X112072Y703920D01*
X112488D01*
X112738Y704004D01*
X112947Y704212D01*
X113030Y704504D01*
X112905Y704795D01*
X112613Y705004D01*
X112280Y705087D01*
X111947Y705004D01*
X111655Y704795D01*
X111530Y704504D01*
X111613Y704212D01*
X111822Y704004D01*
X112072Y703920D01*
X112488D01*
X112863Y703795D01*
X113113Y703545D01*
X113197Y703254D01*
X113113Y702962D01*
X112905Y702754D01*
X112572Y702629D01*
X112280Y702587D01*
G01X86900Y713200D02*
X84400D01*
G01X86900Y712242D02*
Y714158D01*
G01X84400Y715367D02*
X86900D01*
Y716367D01*
X86775Y716700D01*
X86483Y716950D01*
X86150Y717033D01*
X85817Y716950D01*
X85567Y716742D01*
X85442Y716367D01*
Y715367D01*
G01X84400Y719200D02*
X86900D01*
X86400Y718700D01*
G01X84400D02*
Y719700D01*
G01Y722700D02*
X86900D01*
X85108Y721158D01*
Y723242D01*
G01X86900Y725200D02*
X86817Y724867D01*
X86608Y724617D01*
X86358Y724450D01*
X86025Y724325D01*
X85650Y724283D01*
X85275Y724325D01*
X84942Y724450D01*
X84692Y724617D01*
X84483Y724867D01*
X84400Y725200D01*
X84483Y725533D01*
X84692Y725783D01*
X84942Y725950D01*
X85275Y726075D01*
X85650Y726117D01*
X86025Y726075D01*
X86358Y725950D01*
X86608Y725783D01*
X86817Y725533D01*
X86900Y725200D01*
G01X145824Y838459D02*
X146074Y838584D01*
X146366Y838667D01*
X146699D01*
X147074Y838542D01*
X147366Y838334D01*
X147574Y838084D01*
X147741Y837667D01*
X147783Y837292D01*
X147699Y836917D01*
X147574Y836667D01*
X147324Y836417D01*
X147033Y836250D01*
X146741Y836167D01*
X146449D01*
X146158Y836250D01*
X145908Y836375D01*
X145699Y836542D01*
G01X143741Y836167D02*
Y838667D01*
X144241Y838167D01*
G01Y836167D02*
X143241D01*
G01X140741D02*
X140449Y836209D01*
X140116Y836334D01*
X139908Y836542D01*
X139824Y836834D01*
X139908Y837125D01*
X140158Y837375D01*
X140533Y837500D01*
X140949D01*
X141199Y837584D01*
X141408Y837792D01*
X141491Y838084D01*
X141366Y838375D01*
X141074Y838584D01*
X140741Y838667D01*
X140408Y838584D01*
X140116Y838375D01*
X139991Y838084D01*
X140074Y837792D01*
X140283Y837584D01*
X140533Y837500D01*
X140949D01*
X141324Y837375D01*
X141574Y837125D01*
X141658Y836834D01*
X141574Y836542D01*
X141366Y836334D01*
X141033Y836209D01*
X140741Y836167D01*
G01X137741D02*
Y838667D01*
X138241Y838167D01*
G01Y836167D02*
X137241D01*
G01X145755Y834890D02*
X146005Y835015D01*
X146297Y835098D01*
X146630D01*
X147005Y834973D01*
X147297Y834765D01*
X147505Y834515D01*
X147672Y834098D01*
X147714Y833723D01*
X147630Y833348D01*
X147505Y833098D01*
X147255Y832848D01*
X146964Y832681D01*
X146672Y832598D01*
X146380D01*
X146089Y832681D01*
X145839Y832806D01*
X145630Y832973D01*
G01X143672Y832598D02*
Y835098D01*
X144172Y834598D01*
G01Y832598D02*
X143172D01*
G01X140672D02*
X140380Y832640D01*
X140047Y832765D01*
X139839Y832973D01*
X139755Y833265D01*
X139839Y833556D01*
X140089Y833806D01*
X140464Y833931D01*
X140880D01*
X141130Y834015D01*
X141339Y834223D01*
X141422Y834515D01*
X141297Y834806D01*
X141005Y835015D01*
X140672Y835098D01*
X140339Y835015D01*
X140047Y834806D01*
X139922Y834515D01*
X140005Y834223D01*
X140214Y834015D01*
X140464Y833931D01*
X140880D01*
X141255Y833806D01*
X141505Y833556D01*
X141589Y833265D01*
X141505Y832973D01*
X141297Y832765D01*
X140964Y832640D01*
X140672Y832598D01*
G01X138464Y834681D02*
X138214Y834931D01*
X137922Y835056D01*
X137589Y835098D01*
X137172Y835015D01*
X136880Y834806D01*
X136797Y834556D01*
X136839Y834306D01*
X137005Y834098D01*
X137839Y833681D01*
X138214Y833390D01*
X138464Y832973D01*
X138547Y832598D01*
X136797D01*
G01X145673Y830953D02*
X145923Y831078D01*
X146215Y831161D01*
X146548D01*
X146923Y831036D01*
X147215Y830828D01*
X147423Y830578D01*
X147590Y830161D01*
X147632Y829786D01*
X147548Y829411D01*
X147423Y829161D01*
X147173Y828911D01*
X146882Y828744D01*
X146590Y828661D01*
X146298D01*
X146007Y828744D01*
X145757Y828869D01*
X145548Y829036D01*
G01X143590Y828661D02*
Y831161D01*
X144090Y830661D01*
G01Y828661D02*
X143090D01*
G01X140590D02*
X140298Y828703D01*
X139965Y828828D01*
X139757Y829036D01*
X139673Y829328D01*
X139757Y829619D01*
X140007Y829869D01*
X140382Y829994D01*
X140798D01*
X141048Y830078D01*
X141257Y830286D01*
X141340Y830578D01*
X141215Y830869D01*
X140923Y831078D01*
X140590Y831161D01*
X140257Y831078D01*
X139965Y830869D01*
X139840Y830578D01*
X139923Y830286D01*
X140132Y830078D01*
X140382Y829994D01*
X140798D01*
X141173Y829869D01*
X141423Y829619D01*
X141507Y829328D01*
X141423Y829036D01*
X141215Y828828D01*
X140882Y828703D01*
X140590Y828661D01*
G01X138507Y829161D02*
X138257Y828869D01*
X137923Y828703D01*
X137548Y828661D01*
X137215Y828703D01*
X136882Y828911D01*
X136673Y829161D01*
X136632Y829411D01*
X136715Y829703D01*
X137007Y829911D01*
X137298Y829994D01*
X137673D01*
G01X137298D02*
X137048Y830119D01*
X136840Y830328D01*
X136757Y830578D01*
X136840Y830828D01*
X137048Y831036D01*
X137423Y831161D01*
X137798Y831119D01*
X138173Y830953D01*
G01X146545Y854483D02*
X146795Y854608D01*
X147087Y854691D01*
X147420D01*
X147795Y854566D01*
X148087Y854358D01*
X148295Y854108D01*
X148462Y853691D01*
X148504Y853316D01*
X148420Y852941D01*
X148295Y852691D01*
X148045Y852441D01*
X147754Y852274D01*
X147462Y852191D01*
X147170D01*
X146879Y852274D01*
X146629Y852399D01*
X146420Y852566D01*
G01X144462Y852191D02*
Y854691D01*
X144962Y854191D01*
G01Y852191D02*
X143962D01*
G01X141545D02*
X141462Y852733D01*
X141337Y853191D01*
X141170Y853608D01*
X140962Y854066D01*
X140629Y854691D01*
X142295D01*
G01X138462Y852191D02*
X138170Y852233D01*
X137837Y852358D01*
X137629Y852566D01*
X137545Y852858D01*
X137629Y853149D01*
X137879Y853399D01*
X138254Y853524D01*
X138670D01*
X138920Y853608D01*
X139129Y853816D01*
X139212Y854108D01*
X139087Y854399D01*
X138795Y854608D01*
X138462Y854691D01*
X138129Y854608D01*
X137837Y854399D01*
X137712Y854108D01*
X137795Y853816D01*
X138004Y853608D01*
X138254Y853524D01*
X138670D01*
X139045Y853399D01*
X139295Y853149D01*
X139379Y852858D01*
X139295Y852566D01*
X139087Y852358D01*
X138754Y852233D01*
X138462Y852191D01*
G01X146667Y850464D02*
X146917Y850589D01*
X147209Y850672D01*
X147542D01*
X147917Y850547D01*
X148209Y850339D01*
X148417Y850089D01*
X148584Y849672D01*
X148626Y849297D01*
X148542Y848922D01*
X148417Y848672D01*
X148167Y848422D01*
X147876Y848255D01*
X147584Y848172D01*
X147292D01*
X147001Y848255D01*
X146751Y848380D01*
X146542Y848547D01*
G01X144584Y848172D02*
Y850672D01*
X145084Y850172D01*
G01Y848172D02*
X144084D01*
G01X141667D02*
X141584Y848714D01*
X141459Y849172D01*
X141292Y849589D01*
X141084Y850047D01*
X140751Y850672D01*
X142417D01*
G01X139292Y848464D02*
X139001Y848255D01*
X138667Y848172D01*
X138334Y848255D01*
X138042Y848505D01*
X137834Y848880D01*
X137751Y849255D01*
Y849714D01*
X137834Y850089D01*
X138042Y850422D01*
X138292Y850589D01*
X138584Y850672D01*
X138917Y850589D01*
X139167Y850422D01*
X139334Y850172D01*
X139417Y849839D01*
X139334Y849547D01*
X139126Y849255D01*
X138876Y849089D01*
X138584Y849047D01*
X138251Y849130D01*
X138001Y849339D01*
X137751Y849714D01*
G01X145824Y842459D02*
X146074Y842584D01*
X146366Y842667D01*
X146699D01*
X147074Y842542D01*
X147366Y842334D01*
X147574Y842084D01*
X147741Y841667D01*
X147783Y841292D01*
X147699Y840917D01*
X147574Y840667D01*
X147324Y840417D01*
X147033Y840250D01*
X146741Y840167D01*
X146449D01*
X146158Y840250D01*
X145908Y840375D01*
X145699Y840542D01*
G01X143741Y840167D02*
Y842667D01*
X144241Y842167D01*
G01Y840167D02*
X143241D01*
G01X140741D02*
X140449Y840209D01*
X140116Y840334D01*
X139908Y840542D01*
X139824Y840834D01*
X139908Y841125D01*
X140158Y841375D01*
X140533Y841500D01*
X140949D01*
X141199Y841584D01*
X141408Y841792D01*
X141491Y842084D01*
X141366Y842375D01*
X141074Y842584D01*
X140741Y842667D01*
X140408Y842584D01*
X140116Y842375D01*
X139991Y842084D01*
X140074Y841792D01*
X140283Y841584D01*
X140533Y841500D01*
X140949D01*
X141324Y841375D01*
X141574Y841125D01*
X141658Y840834D01*
X141574Y840542D01*
X141366Y840334D01*
X141033Y840209D01*
X140741Y840167D01*
G01X137741Y842667D02*
X138074Y842584D01*
X138324Y842375D01*
X138491Y842125D01*
X138616Y841792D01*
X138658Y841417D01*
X138616Y841042D01*
X138491Y840709D01*
X138324Y840459D01*
X138074Y840250D01*
X137741Y840167D01*
X137408Y840250D01*
X137158Y840459D01*
X136991Y840709D01*
X136866Y841042D01*
X136824Y841417D01*
X136866Y841792D01*
X136991Y842125D01*
X137158Y842375D01*
X137408Y842584D01*
X137741Y842667D01*
G01X187283Y270092D02*
X187533Y270217D01*
X187825Y270300D01*
X188158D01*
X188533Y270175D01*
X188825Y269967D01*
X189033Y269717D01*
X189200Y269300D01*
X189242Y268925D01*
X189158Y268550D01*
X189033Y268300D01*
X188783Y268050D01*
X188492Y267883D01*
X188200Y267800D01*
X187908D01*
X187617Y267883D01*
X187367Y268008D01*
X187158Y268175D01*
G01X185200Y267800D02*
Y270300D01*
X185700Y269800D01*
G01Y267800D02*
X184700D01*
G01X182283D02*
X182200Y268342D01*
X182075Y268800D01*
X181908Y269217D01*
X181700Y269675D01*
X181367Y270300D01*
X183033D01*
G01X179992Y269883D02*
X179742Y270133D01*
X179450Y270258D01*
X179117Y270300D01*
X178700Y270217D01*
X178408Y270008D01*
X178325Y269758D01*
X178367Y269508D01*
X178533Y269300D01*
X179367Y268883D01*
X179742Y268592D01*
X179992Y268175D01*
X180075Y267800D01*
X178325D01*
G01X185733Y262867D02*
Y265367D01*
X184692D01*
X184358Y265242D01*
X184150Y265075D01*
X184067Y264742D01*
X184150Y264409D01*
X184400Y264200D01*
X184692Y264075D01*
X185733D01*
G01X184692D02*
X184067Y262867D01*
G01X182608Y263159D02*
X182317Y262950D01*
X181983Y262867D01*
X181650Y262950D01*
X181358Y263200D01*
X181150Y263575D01*
X181067Y263950D01*
Y264409D01*
X181150Y264784D01*
X181358Y265117D01*
X181608Y265284D01*
X181900Y265367D01*
X182233Y265284D01*
X182483Y265117D01*
X182650Y264867D01*
X182733Y264534D01*
X182650Y264242D01*
X182442Y263950D01*
X182192Y263784D01*
X181900Y263742D01*
X181567Y263825D01*
X181317Y264034D01*
X181067Y264409D01*
G01X178900Y262867D02*
X178608Y262909D01*
X178275Y263034D01*
X178067Y263242D01*
X177983Y263534D01*
X178067Y263825D01*
X178317Y264075D01*
X178692Y264200D01*
X179108D01*
X179358Y264284D01*
X179567Y264492D01*
X179650Y264784D01*
X179525Y265075D01*
X179233Y265284D01*
X178900Y265367D01*
X178567Y265284D01*
X178275Y265075D01*
X178150Y264784D01*
X178233Y264492D01*
X178442Y264284D01*
X178692Y264200D01*
X179108D01*
X179483Y264075D01*
X179733Y263825D01*
X179817Y263534D01*
X179733Y263242D01*
X179525Y263034D01*
X179192Y262909D01*
X178900Y262867D01*
G01X186133Y257367D02*
Y259867D01*
X185092D01*
X184758Y259742D01*
X184550Y259575D01*
X184467Y259242D01*
X184550Y258909D01*
X184800Y258700D01*
X185092Y258575D01*
X186133D01*
G01X185092D02*
X184467Y257367D01*
G01X183008Y257659D02*
X182717Y257450D01*
X182383Y257367D01*
X182050Y257450D01*
X181758Y257700D01*
X181550Y258075D01*
X181467Y258450D01*
Y258909D01*
X181550Y259284D01*
X181758Y259617D01*
X182008Y259784D01*
X182300Y259867D01*
X182633Y259784D01*
X182883Y259617D01*
X183050Y259367D01*
X183133Y259034D01*
X183050Y258742D01*
X182842Y258450D01*
X182592Y258284D01*
X182300Y258242D01*
X181967Y258325D01*
X181717Y258534D01*
X181467Y258909D01*
G01X180217Y257742D02*
X179967Y257534D01*
X179675Y257409D01*
X179300Y257367D01*
X178925Y257450D01*
X178633Y257617D01*
X178425Y257909D01*
X178383Y258242D01*
X178467Y258575D01*
X178675Y258784D01*
X178967Y258950D01*
X179258Y258992D01*
X179550Y258950D01*
X179925Y258784D01*
X179800Y259867D01*
X178675D01*
G01X188933Y273100D02*
Y275600D01*
X187892D01*
X187558Y275475D01*
X187350Y275308D01*
X187267Y274975D01*
X187350Y274642D01*
X187600Y274433D01*
X187892Y274308D01*
X188933D01*
G01X187892D02*
X187267Y273100D01*
G01X185808Y273392D02*
X185517Y273183D01*
X185183Y273100D01*
X184850Y273183D01*
X184558Y273433D01*
X184350Y273808D01*
X184267Y274183D01*
Y274642D01*
X184350Y275017D01*
X184558Y275350D01*
X184808Y275517D01*
X185100Y275600D01*
X185433Y275517D01*
X185683Y275350D01*
X185850Y275100D01*
X185933Y274767D01*
X185850Y274475D01*
X185642Y274183D01*
X185392Y274017D01*
X185100Y273975D01*
X184767Y274058D01*
X184517Y274267D01*
X184267Y274642D01*
G01X182808Y273392D02*
X182517Y273183D01*
X182183Y273100D01*
X181850Y273183D01*
X181558Y273433D01*
X181350Y273808D01*
X181267Y274183D01*
Y274642D01*
X181350Y275017D01*
X181558Y275350D01*
X181808Y275517D01*
X182100Y275600D01*
X182433Y275517D01*
X182683Y275350D01*
X182850Y275100D01*
X182933Y274767D01*
X182850Y274475D01*
X182642Y274183D01*
X182392Y274017D01*
X182100Y273975D01*
X181767Y274058D01*
X181517Y274267D01*
X181267Y274642D01*
G01X198600Y243567D02*
X201100D01*
Y244608D01*
X200975Y244942D01*
X200808Y245150D01*
X200475Y245233D01*
X200142Y245150D01*
X199933Y244900D01*
X199808Y244608D01*
Y243567D01*
G01Y244608D02*
X198600Y245233D01*
G01X198892Y246692D02*
X198683Y246983D01*
X198600Y247317D01*
X198683Y247650D01*
X198933Y247942D01*
X199308Y248150D01*
X199683Y248233D01*
X200142D01*
X200517Y248150D01*
X200850Y247942D01*
X201017Y247692D01*
X201100Y247400D01*
X201017Y247067D01*
X200850Y246817D01*
X200600Y246650D01*
X200267Y246567D01*
X199975Y246650D01*
X199683Y246858D01*
X199517Y247108D01*
X199475Y247400D01*
X199558Y247733D01*
X199767Y247983D01*
X200142Y248233D01*
G01X198600Y250317D02*
X199142Y250400D01*
X199600Y250525D01*
X200017Y250692D01*
X200475Y250900D01*
X201100Y251233D01*
Y249567D01*
G01X194133Y243400D02*
Y245900D01*
X193092D01*
X192758Y245775D01*
X192550Y245608D01*
X192467Y245275D01*
X192550Y244942D01*
X192800Y244733D01*
X193092Y244608D01*
X194133D01*
G01X193092D02*
X192467Y243400D01*
G01X191008Y243692D02*
X190717Y243483D01*
X190383Y243400D01*
X190050Y243483D01*
X189758Y243733D01*
X189550Y244108D01*
X189467Y244483D01*
Y244942D01*
X189550Y245317D01*
X189758Y245650D01*
X190008Y245817D01*
X190300Y245900D01*
X190633Y245817D01*
X190883Y245650D01*
X191050Y245400D01*
X191133Y245067D01*
X191050Y244775D01*
X190842Y244483D01*
X190592Y244317D01*
X190300Y244275D01*
X189967Y244358D01*
X189717Y244567D01*
X189467Y244942D01*
G01X188092Y244442D02*
X187800Y244733D01*
X187550Y244900D01*
X187217Y244983D01*
X186925Y244900D01*
X186717Y244733D01*
X186550Y244483D01*
X186508Y244192D01*
X186550Y243942D01*
X186717Y243692D01*
X186967Y243483D01*
X187258Y243400D01*
X187592Y243483D01*
X187883Y243733D01*
X188050Y244108D01*
X188092Y244525D01*
X188008Y245067D01*
X187883Y245358D01*
X187675Y245650D01*
X187383Y245858D01*
X187092Y245900D01*
X186800Y245817D01*
X186592Y245608D01*
G01X193083Y234092D02*
X193333Y234217D01*
X193625Y234300D01*
X193958D01*
X194333Y234175D01*
X194625Y233967D01*
X194833Y233717D01*
X195000Y233300D01*
X195042Y232925D01*
X194958Y232550D01*
X194833Y232300D01*
X194583Y232050D01*
X194292Y231883D01*
X194000Y231800D01*
X193708D01*
X193417Y231883D01*
X193167Y232008D01*
X192958Y232175D01*
G01X191000Y231800D02*
Y234300D01*
X191500Y233800D01*
G01Y231800D02*
X190500D01*
G01X188792Y232842D02*
X188500Y233133D01*
X188250Y233300D01*
X187917Y233383D01*
X187625Y233300D01*
X187417Y233133D01*
X187250Y232883D01*
X187208Y232592D01*
X187250Y232342D01*
X187417Y232092D01*
X187667Y231883D01*
X187958Y231800D01*
X188292Y231883D01*
X188583Y232133D01*
X188750Y232508D01*
X188792Y232925D01*
X188708Y233467D01*
X188583Y233758D01*
X188375Y234050D01*
X188083Y234258D01*
X187792Y234300D01*
X187500Y234217D01*
X187292Y234008D01*
G01X184500Y231800D02*
Y234300D01*
X186042Y232508D01*
X183958D01*
G01X166250Y228361D02*
Y226569D01*
X166083Y226194D01*
X165750Y225944D01*
X165333Y225861D01*
X164916Y225944D01*
X164583Y226194D01*
X164416Y226569D01*
Y228361D01*
G01X163125Y227944D02*
X162875Y228194D01*
X162583Y228319D01*
X162250Y228361D01*
X161833Y228278D01*
X161541Y228069D01*
X161458Y227819D01*
X161500Y227569D01*
X161666Y227361D01*
X162500Y226944D01*
X162875Y226653D01*
X163125Y226236D01*
X163208Y225861D01*
X161458D01*
G01X197433Y293900D02*
Y296400D01*
X196392D01*
X196058Y296275D01*
X195850Y296108D01*
X195767Y295775D01*
X195850Y295442D01*
X196100Y295233D01*
X196392Y295108D01*
X197433D01*
G01X196392D02*
X195767Y293900D01*
G01X193600D02*
Y296400D01*
X194100Y295900D01*
G01Y293900D02*
X193100D01*
G01X190600Y296400D02*
X190933Y296317D01*
X191183Y296108D01*
X191350Y295858D01*
X191475Y295525D01*
X191517Y295150D01*
X191475Y294775D01*
X191350Y294442D01*
X191183Y294192D01*
X190933Y293983D01*
X190600Y293900D01*
X190267Y293983D01*
X190017Y294192D01*
X189850Y294442D01*
X189725Y294775D01*
X189683Y295150D01*
X189725Y295525D01*
X189850Y295858D01*
X190017Y296108D01*
X190267Y296317D01*
X190600Y296400D01*
G01X188392Y294942D02*
X188100Y295233D01*
X187850Y295400D01*
X187517Y295483D01*
X187225Y295400D01*
X187017Y295233D01*
X186850Y294983D01*
X186808Y294692D01*
X186850Y294442D01*
X187017Y294192D01*
X187267Y293983D01*
X187558Y293900D01*
X187892Y293983D01*
X188183Y294233D01*
X188350Y294608D01*
X188392Y295025D01*
X188308Y295567D01*
X188183Y295858D01*
X187975Y296150D01*
X187683Y296358D01*
X187392Y296400D01*
X187100Y296317D01*
X186892Y296108D01*
G01X200933Y288500D02*
Y291000D01*
X199892D01*
X199558Y290875D01*
X199350Y290708D01*
X199267Y290375D01*
X199350Y290042D01*
X199600Y289833D01*
X199892Y289708D01*
X200933D01*
G01X199892D02*
X199267Y288500D01*
G01X197100D02*
Y291000D01*
X197600Y290500D01*
G01Y288500D02*
X196600D01*
G01X194100Y291000D02*
X194433Y290917D01*
X194683Y290708D01*
X194850Y290458D01*
X194975Y290125D01*
X195017Y289750D01*
X194975Y289375D01*
X194850Y289042D01*
X194683Y288792D01*
X194433Y288583D01*
X194100Y288500D01*
X193767Y288583D01*
X193517Y288792D01*
X193350Y289042D01*
X193225Y289375D01*
X193183Y289750D01*
X193225Y290125D01*
X193350Y290458D01*
X193517Y290708D01*
X193767Y290917D01*
X194100Y291000D01*
G01X191100Y288500D02*
Y291000D01*
X191600Y290500D01*
G01Y288500D02*
X190600D01*
G01X192683Y485492D02*
X192933Y485617D01*
X193225Y485700D01*
X193558D01*
X193933Y485575D01*
X194225Y485367D01*
X194433Y485117D01*
X194600Y484700D01*
X194642Y484325D01*
X194558Y483950D01*
X194433Y483700D01*
X194183Y483450D01*
X193892Y483283D01*
X193600Y483200D01*
X193308D01*
X193017Y483283D01*
X192767Y483408D01*
X192558Y483575D01*
G01X190600Y483200D02*
Y485700D01*
X191100Y485200D01*
G01Y483200D02*
X190100D01*
G01X187600D02*
Y485700D01*
X188100Y485200D01*
G01Y483200D02*
X187100D01*
G01X185308Y483492D02*
X185017Y483283D01*
X184683Y483200D01*
X184350Y483283D01*
X184058Y483533D01*
X183850Y483908D01*
X183767Y484283D01*
Y484742D01*
X183850Y485117D01*
X184058Y485450D01*
X184308Y485617D01*
X184600Y485700D01*
X184933Y485617D01*
X185183Y485450D01*
X185350Y485200D01*
X185433Y484867D01*
X185350Y484575D01*
X185142Y484283D01*
X184892Y484117D01*
X184600Y484075D01*
X184267Y484158D01*
X184017Y484367D01*
X183767Y484742D01*
G01X189983Y481592D02*
X190233Y481717D01*
X190525Y481800D01*
X190858D01*
X191233Y481675D01*
X191525Y481467D01*
X191733Y481217D01*
X191900Y480800D01*
X191942Y480425D01*
X191858Y480050D01*
X191733Y479800D01*
X191483Y479550D01*
X191192Y479383D01*
X190900Y479300D01*
X190608D01*
X190317Y479383D01*
X190067Y479508D01*
X189858Y479675D01*
G01X187900Y479300D02*
Y481800D01*
X188400Y481300D01*
G01Y479300D02*
X187400D01*
G01X185692Y481383D02*
X185442Y481633D01*
X185150Y481758D01*
X184817Y481800D01*
X184400Y481717D01*
X184108Y481508D01*
X184025Y481258D01*
X184067Y481008D01*
X184233Y480800D01*
X185067Y480383D01*
X185442Y480092D01*
X185692Y479675D01*
X185775Y479300D01*
X184025D01*
G01X181900D02*
Y481800D01*
X182400Y481300D01*
G01Y479300D02*
X181400D01*
G01X174583Y429159D02*
X174833Y429284D01*
X175125Y429367D01*
X175458D01*
X175833Y429242D01*
X176125Y429034D01*
X176333Y428784D01*
X176500Y428367D01*
X176542Y427992D01*
X176458Y427617D01*
X176333Y427367D01*
X176083Y427117D01*
X175792Y426950D01*
X175500Y426867D01*
X175208D01*
X174917Y426950D01*
X174667Y427075D01*
X174458Y427242D01*
G01X172500Y426867D02*
Y429367D01*
X173000Y428867D01*
G01Y426867D02*
X172000D01*
G01X169500D02*
Y429367D01*
X170000Y428867D01*
G01Y426867D02*
X169000D01*
G01X167292Y428950D02*
X167042Y429200D01*
X166750Y429325D01*
X166417Y429367D01*
X166000Y429284D01*
X165708Y429075D01*
X165625Y428825D01*
X165667Y428575D01*
X165833Y428367D01*
X166667Y427950D01*
X167042Y427659D01*
X167292Y427242D01*
X167375Y426867D01*
X165625D01*
G01X160883Y460859D02*
X161133Y460984D01*
X161425Y461067D01*
X161758D01*
X162133Y460942D01*
X162425Y460734D01*
X162633Y460484D01*
X162800Y460067D01*
X162842Y459692D01*
X162758Y459317D01*
X162633Y459067D01*
X162383Y458817D01*
X162092Y458650D01*
X161800Y458567D01*
X161508D01*
X161217Y458650D01*
X160967Y458775D01*
X160758Y458942D01*
G01X158800Y458567D02*
Y461067D01*
X159300Y460567D01*
G01Y458567D02*
X158300D01*
G01X155800D02*
Y461067D01*
X156300Y460567D01*
G01Y458567D02*
X155300D01*
G01X152300D02*
Y461067D01*
X153842Y459275D01*
X151758D01*
G01X162623Y436935D02*
X162873Y437060D01*
X163165Y437143D01*
X163498D01*
X163873Y437018D01*
X164165Y436810D01*
X164373Y436560D01*
X164540Y436143D01*
X164582Y435768D01*
X164498Y435393D01*
X164373Y435143D01*
X164123Y434893D01*
X163832Y434726D01*
X163540Y434643D01*
X163248D01*
X162957Y434726D01*
X162707Y434851D01*
X162498Y435018D01*
G01X160540Y434643D02*
Y437143D01*
X161040Y436643D01*
G01Y434643D02*
X160040D01*
G01X157540D02*
Y437143D01*
X158040Y436643D01*
G01Y434643D02*
X157040D01*
G01X155332Y435685D02*
X155040Y435976D01*
X154790Y436143D01*
X154457Y436226D01*
X154165Y436143D01*
X153957Y435976D01*
X153790Y435726D01*
X153748Y435435D01*
X153790Y435185D01*
X153957Y434935D01*
X154207Y434726D01*
X154498Y434643D01*
X154832Y434726D01*
X155123Y434976D01*
X155290Y435351D01*
X155332Y435768D01*
X155248Y436310D01*
X155123Y436601D01*
X154915Y436893D01*
X154623Y437101D01*
X154332Y437143D01*
X154040Y437060D01*
X153832Y436851D01*
G01X226833Y485300D02*
Y487800D01*
X225792D01*
X225458Y487675D01*
X225250Y487508D01*
X225167Y487175D01*
X225250Y486842D01*
X225500Y486633D01*
X225792Y486508D01*
X226833D01*
G01X225792D02*
X225167Y485300D01*
G01X223000D02*
Y487800D01*
X223500Y487300D01*
G01Y485300D02*
X222500D01*
G01X220917Y485800D02*
X220667Y485508D01*
X220333Y485342D01*
X219958Y485300D01*
X219625Y485342D01*
X219292Y485550D01*
X219083Y485800D01*
X219042Y486050D01*
X219125Y486342D01*
X219417Y486550D01*
X219708Y486633D01*
X220083D01*
G01X219708D02*
X219458Y486758D01*
X219250Y486967D01*
X219167Y487217D01*
X219250Y487467D01*
X219458Y487675D01*
X219833Y487800D01*
X220208Y487758D01*
X220583Y487592D01*
G01X217000Y487800D02*
X217333Y487717D01*
X217583Y487508D01*
X217750Y487258D01*
X217875Y486925D01*
X217917Y486550D01*
X217875Y486175D01*
X217750Y485842D01*
X217583Y485592D01*
X217333Y485383D01*
X217000Y485300D01*
X216667Y485383D01*
X216417Y485592D01*
X216250Y485842D01*
X216125Y486175D01*
X216083Y486550D01*
X216125Y486925D01*
X216250Y487258D01*
X216417Y487508D01*
X216667Y487717D01*
X217000Y487800D01*
G01X152503Y476629D02*
X150003D01*
G01X152503Y475671D02*
Y477587D01*
G01X150003Y478796D02*
X152503D01*
Y479796D01*
X152378Y480129D01*
X152086Y480379D01*
X151753Y480462D01*
X151420Y480379D01*
X151170Y480171D01*
X151045Y479796D01*
Y478796D01*
G01X150003Y482629D02*
X152503D01*
X152003Y482129D01*
G01X150003D02*
Y483129D01*
G01Y485629D02*
X152503D01*
X152003Y485129D01*
G01X150003D02*
Y486129D01*
G01X184100Y458300D02*
Y455800D01*
G01X185058Y458300D02*
X183142D01*
G01X181933Y455800D02*
Y458300D01*
X180933D01*
X180600Y458175D01*
X180350Y457883D01*
X180267Y457550D01*
X180350Y457217D01*
X180558Y456967D01*
X180933Y456842D01*
X181933D01*
G01X178100Y455800D02*
Y458300D01*
X178600Y457800D01*
G01Y455800D02*
X177600D01*
G01X175892Y457883D02*
X175642Y458133D01*
X175350Y458258D01*
X175017Y458300D01*
X174600Y458217D01*
X174308Y458008D01*
X174225Y457758D01*
X174267Y457508D01*
X174433Y457300D01*
X175267Y456883D01*
X175642Y456592D01*
X175892Y456175D01*
X175975Y455800D01*
X174225D01*
G01X162367Y470400D02*
X159867D01*
G01X162367Y469442D02*
Y471358D01*
G01X159867Y472567D02*
X162367D01*
Y473567D01*
X162242Y473900D01*
X161950Y474150D01*
X161617Y474233D01*
X161284Y474150D01*
X161034Y473942D01*
X160909Y473567D01*
Y472567D01*
G01X159867Y476400D02*
X162367D01*
X161867Y475900D01*
G01X159867D02*
Y476900D01*
G01X160909Y478608D02*
X161200Y478900D01*
X161367Y479150D01*
X161450Y479483D01*
X161367Y479775D01*
X161200Y479983D01*
X160950Y480150D01*
X160659Y480192D01*
X160409Y480150D01*
X160159Y479983D01*
X159950Y479733D01*
X159867Y479442D01*
X159950Y479108D01*
X160200Y478817D01*
X160575Y478650D01*
X160992Y478608D01*
X161534Y478692D01*
X161825Y478817D01*
X162117Y479025D01*
X162325Y479317D01*
X162367Y479608D01*
X162284Y479900D01*
X162075Y480108D01*
G01X180167Y460600D02*
X177667D01*
G01X180167Y459642D02*
Y461558D01*
G01X177667Y462767D02*
X180167D01*
Y463767D01*
X180042Y464100D01*
X179750Y464350D01*
X179417Y464433D01*
X179084Y464350D01*
X178834Y464142D01*
X178709Y463767D01*
Y462767D01*
G01X177667Y466600D02*
X180167D01*
X179667Y466100D01*
G01X177667D02*
Y467100D01*
G01Y469517D02*
X178209Y469600D01*
X178667Y469725D01*
X179084Y469892D01*
X179542Y470100D01*
X180167Y470433D01*
Y468767D01*
G01X199600Y464000D02*
Y461500D01*
G01X200558Y464000D02*
X198642D01*
G01X197433Y461500D02*
Y464000D01*
X196433D01*
X196100Y463875D01*
X195850Y463583D01*
X195767Y463250D01*
X195850Y462917D01*
X196058Y462667D01*
X196433Y462542D01*
X197433D01*
G01X194392Y463583D02*
X194142Y463833D01*
X193850Y463958D01*
X193517Y464000D01*
X193100Y463917D01*
X192808Y463708D01*
X192725Y463458D01*
X192767Y463208D01*
X192933Y463000D01*
X193767Y462583D01*
X194142Y462292D01*
X194392Y461875D01*
X194475Y461500D01*
X192725D01*
G01X190600D02*
Y464000D01*
X191100Y463500D01*
G01Y461500D02*
X190100D01*
G01X176000Y452700D02*
Y450200D01*
G01X176958Y452700D02*
X175042D01*
G01X173833Y450200D02*
Y452700D01*
X172833D01*
X172500Y452575D01*
X172250Y452283D01*
X172167Y451950D01*
X172250Y451617D01*
X172458Y451367D01*
X172833Y451242D01*
X173833D01*
G01X170792Y452283D02*
X170542Y452533D01*
X170250Y452658D01*
X169917Y452700D01*
X169500Y452617D01*
X169208Y452408D01*
X169125Y452158D01*
X169167Y451908D01*
X169333Y451700D01*
X170167Y451283D01*
X170542Y450992D01*
X170792Y450575D01*
X170875Y450200D01*
X169125D01*
G01X167792Y452283D02*
X167542Y452533D01*
X167250Y452658D01*
X166917Y452700D01*
X166500Y452617D01*
X166208Y452408D01*
X166125Y452158D01*
X166167Y451908D01*
X166333Y451700D01*
X167167Y451283D01*
X167542Y450992D01*
X167792Y450575D01*
X167875Y450200D01*
X166125D01*
G01X205800Y479600D02*
Y477100D01*
G01X206758Y479600D02*
X204842D01*
G01X203633Y477100D02*
Y479600D01*
X202633D01*
X202300Y479475D01*
X202050Y479183D01*
X201967Y478850D01*
X202050Y478517D01*
X202258Y478267D01*
X202633Y478142D01*
X203633D01*
G01X200592Y479183D02*
X200342Y479433D01*
X200050Y479558D01*
X199717Y479600D01*
X199300Y479517D01*
X199008Y479308D01*
X198925Y479058D01*
X198967Y478808D01*
X199133Y478600D01*
X199967Y478183D01*
X200342Y477892D01*
X200592Y477475D01*
X200675Y477100D01*
X198925D01*
G01X196300D02*
Y479600D01*
X197842Y477808D01*
X195758D01*
G01X218600Y479200D02*
Y476700D01*
G01X219558Y479200D02*
X217642D01*
G01X216433Y476700D02*
Y479200D01*
X215433D01*
X215100Y479075D01*
X214850Y478783D01*
X214767Y478450D01*
X214850Y478117D01*
X215058Y477867D01*
X215433Y477742D01*
X216433D01*
G01X213392Y478783D02*
X213142Y479033D01*
X212850Y479158D01*
X212517Y479200D01*
X212100Y479117D01*
X211808Y478908D01*
X211725Y478658D01*
X211767Y478408D01*
X211933Y478200D01*
X212767Y477783D01*
X213142Y477492D01*
X213392Y477075D01*
X213475Y476700D01*
X211725D01*
G01X210517Y477075D02*
X210267Y476867D01*
X209975Y476742D01*
X209600Y476700D01*
X209225Y476783D01*
X208933Y476950D01*
X208725Y477242D01*
X208683Y477575D01*
X208767Y477908D01*
X208975Y478117D01*
X209267Y478283D01*
X209558Y478325D01*
X209850Y478283D01*
X210225Y478117D01*
X210100Y479200D01*
X208975D01*
G01X213300Y464400D02*
X210800D01*
G01X213300Y463442D02*
Y465358D01*
G01X210800Y466567D02*
X213300D01*
Y467567D01*
X213175Y467900D01*
X212883Y468150D01*
X212550Y468233D01*
X212217Y468150D01*
X211967Y467942D01*
X211842Y467567D01*
Y466567D01*
G01X212883Y469608D02*
X213133Y469858D01*
X213258Y470150D01*
X213300Y470483D01*
X213217Y470900D01*
X213008Y471192D01*
X212758Y471275D01*
X212508Y471233D01*
X212300Y471067D01*
X211883Y470233D01*
X211592Y469858D01*
X211175Y469608D01*
X210800Y469525D01*
Y471275D01*
G01Y473317D02*
X211342Y473400D01*
X211800Y473525D01*
X212217Y473692D01*
X212675Y473900D01*
X213300Y474233D01*
Y472567D01*
G01X200100Y450100D02*
X197600D01*
G01X200100Y449142D02*
Y451058D01*
G01X197600Y452267D02*
X200100D01*
Y453267D01*
X199975Y453600D01*
X199683Y453850D01*
X199350Y453933D01*
X199017Y453850D01*
X198767Y453642D01*
X198642Y453267D01*
Y452267D01*
G01X199683Y455308D02*
X199933Y455558D01*
X200058Y455850D01*
X200100Y456183D01*
X200017Y456600D01*
X199808Y456892D01*
X199558Y456975D01*
X199308Y456933D01*
X199100Y456767D01*
X198683Y455933D01*
X198392Y455558D01*
X197975Y455308D01*
X197600Y455225D01*
Y456975D01*
G01Y459100D02*
X197642Y459392D01*
X197767Y459725D01*
X197975Y459933D01*
X198267Y460017D01*
X198558Y459933D01*
X198808Y459683D01*
X198933Y459308D01*
Y458892D01*
X199017Y458642D01*
X199225Y458433D01*
X199517Y458350D01*
X199808Y458475D01*
X200017Y458767D01*
X200100Y459100D01*
X200017Y459433D01*
X199808Y459725D01*
X199517Y459850D01*
X199225Y459767D01*
X199017Y459558D01*
X198933Y459308D01*
Y458892D01*
X198808Y458517D01*
X198558Y458267D01*
X198267Y458183D01*
X197975Y458267D01*
X197767Y458475D01*
X197642Y458808D01*
X197600Y459100D01*
G01X204400Y464900D02*
X201900D01*
G01X204400Y463942D02*
Y465858D01*
G01X201900Y467067D02*
X204400D01*
Y468067D01*
X204275Y468400D01*
X203983Y468650D01*
X203650Y468733D01*
X203317Y468650D01*
X203067Y468442D01*
X202942Y468067D01*
Y467067D01*
G01X203983Y470108D02*
X204233Y470358D01*
X204358Y470650D01*
X204400Y470983D01*
X204317Y471400D01*
X204108Y471692D01*
X203858Y471775D01*
X203608Y471733D01*
X203400Y471567D01*
X202983Y470733D01*
X202692Y470358D01*
X202275Y470108D01*
X201900Y470025D01*
Y471775D01*
G01X202192Y473192D02*
X201983Y473483D01*
X201900Y473817D01*
X201983Y474150D01*
X202233Y474442D01*
X202608Y474650D01*
X202983Y474733D01*
X203442D01*
X203817Y474650D01*
X204150Y474442D01*
X204317Y474192D01*
X204400Y473900D01*
X204317Y473567D01*
X204150Y473317D01*
X203900Y473150D01*
X203567Y473067D01*
X203275Y473150D01*
X202983Y473358D01*
X202817Y473608D01*
X202775Y473900D01*
X202858Y474233D01*
X203067Y474483D01*
X203442Y474733D01*
G01X192800Y432800D02*
X190300D01*
G01X192800Y431842D02*
Y433758D01*
G01X190300Y434967D02*
X192800D01*
Y435967D01*
X192675Y436300D01*
X192383Y436550D01*
X192050Y436633D01*
X191717Y436550D01*
X191467Y436342D01*
X191342Y435967D01*
Y434967D01*
G01X190800Y437883D02*
X190508Y438133D01*
X190342Y438467D01*
X190300Y438842D01*
X190342Y439175D01*
X190550Y439508D01*
X190800Y439717D01*
X191050Y439758D01*
X191342Y439675D01*
X191550Y439383D01*
X191633Y439092D01*
Y438717D01*
G01Y439092D02*
X191758Y439342D01*
X191967Y439550D01*
X192217Y439633D01*
X192467Y439550D01*
X192675Y439342D01*
X192800Y438967D01*
X192758Y438592D01*
X192592Y438217D01*
G01X190800Y440883D02*
X190508Y441133D01*
X190342Y441467D01*
X190300Y441842D01*
X190342Y442175D01*
X190550Y442508D01*
X190800Y442717D01*
X191050Y442758D01*
X191342Y442675D01*
X191550Y442383D01*
X191633Y442092D01*
Y441717D01*
G01Y442092D02*
X191758Y442342D01*
X191967Y442550D01*
X192217Y442633D01*
X192467Y442550D01*
X192675Y442342D01*
X192800Y441967D01*
X192758Y441592D01*
X192592Y441217D01*
G01X188400Y427400D02*
X185900D01*
G01X188400Y426442D02*
Y428358D01*
G01X185900Y429567D02*
X188400D01*
Y430567D01*
X188275Y430900D01*
X187983Y431150D01*
X187650Y431233D01*
X187317Y431150D01*
X187067Y430942D01*
X186942Y430567D01*
Y429567D01*
G01X186400Y432483D02*
X186108Y432733D01*
X185942Y433067D01*
X185900Y433442D01*
X185942Y433775D01*
X186150Y434108D01*
X186400Y434317D01*
X186650Y434358D01*
X186942Y434275D01*
X187150Y433983D01*
X187233Y433692D01*
Y433317D01*
G01Y433692D02*
X187358Y433942D01*
X187567Y434150D01*
X187817Y434233D01*
X188067Y434150D01*
X188275Y433942D01*
X188400Y433567D01*
X188358Y433192D01*
X188192Y432817D01*
G01X186275Y435483D02*
X186067Y435733D01*
X185942Y436025D01*
X185900Y436400D01*
X185983Y436775D01*
X186150Y437067D01*
X186442Y437275D01*
X186775Y437317D01*
X187108Y437233D01*
X187317Y437025D01*
X187483Y436733D01*
X187525Y436442D01*
X187483Y436150D01*
X187317Y435775D01*
X188400Y435900D01*
Y437025D01*
G01X192600Y445600D02*
X190100D01*
G01X192600Y444642D02*
Y446558D01*
G01X190100Y447767D02*
X192600D01*
Y448767D01*
X192475Y449100D01*
X192183Y449350D01*
X191850Y449433D01*
X191517Y449350D01*
X191267Y449142D01*
X191142Y448767D01*
Y447767D01*
G01X190600Y450683D02*
X190308Y450933D01*
X190142Y451267D01*
X190100Y451642D01*
X190142Y451975D01*
X190350Y452308D01*
X190600Y452517D01*
X190850Y452558D01*
X191142Y452475D01*
X191350Y452183D01*
X191433Y451892D01*
Y451517D01*
G01Y451892D02*
X191558Y452142D01*
X191767Y452350D01*
X192017Y452433D01*
X192267Y452350D01*
X192475Y452142D01*
X192600Y451767D01*
X192558Y451392D01*
X192392Y451017D01*
G01X190100Y454517D02*
X190642Y454600D01*
X191100Y454725D01*
X191517Y454892D01*
X191975Y455100D01*
X192600Y455433D01*
Y453767D01*
G01X181511Y447636D02*
Y445136D01*
G01X182469Y447636D02*
X180553D01*
G01X179344Y445136D02*
Y447636D01*
X178344D01*
X178011Y447511D01*
X177761Y447219D01*
X177678Y446886D01*
X177761Y446553D01*
X177969Y446303D01*
X178344Y446178D01*
X179344D01*
G01X176428Y445636D02*
X176178Y445344D01*
X175844Y445178D01*
X175469Y445136D01*
X175136Y445178D01*
X174803Y445386D01*
X174594Y445636D01*
X174553Y445886D01*
X174636Y446178D01*
X174928Y446386D01*
X175219Y446469D01*
X175594D01*
G01X175219D02*
X174969Y446594D01*
X174761Y446803D01*
X174678Y447053D01*
X174761Y447303D01*
X174969Y447511D01*
X175344Y447636D01*
X175719Y447594D01*
X176094Y447428D01*
G01X173219Y445428D02*
X172928Y445219D01*
X172594Y445136D01*
X172261Y445219D01*
X171969Y445469D01*
X171761Y445844D01*
X171678Y446219D01*
Y446678D01*
X171761Y447053D01*
X171969Y447386D01*
X172219Y447553D01*
X172511Y447636D01*
X172844Y447553D01*
X173094Y447386D01*
X173261Y447136D01*
X173344Y446803D01*
X173261Y446511D01*
X173053Y446219D01*
X172803Y446053D01*
X172511Y446011D01*
X172178Y446094D01*
X171928Y446303D01*
X171678Y446678D01*
G01X156667Y480300D02*
X154167D01*
G01X156667Y479342D02*
Y481258D01*
G01X154167Y482467D02*
X156667D01*
Y483467D01*
X156542Y483800D01*
X156250Y484050D01*
X155917Y484133D01*
X155584Y484050D01*
X155334Y483842D01*
X155209Y483467D01*
Y482467D01*
G01X154542Y485383D02*
X154334Y485633D01*
X154209Y485925D01*
X154167Y486300D01*
X154250Y486675D01*
X154417Y486967D01*
X154709Y487175D01*
X155042Y487217D01*
X155375Y487133D01*
X155584Y486925D01*
X155750Y486633D01*
X155792Y486342D01*
X155750Y486050D01*
X155584Y485675D01*
X156667Y485800D01*
Y486925D01*
G01X154167Y489800D02*
X156667D01*
X154875Y488258D01*
Y490342D01*
G01X207600Y450200D02*
X205100D01*
G01X207600Y449242D02*
Y451158D01*
G01X205100Y452367D02*
X207600D01*
Y453367D01*
X207475Y453700D01*
X207183Y453950D01*
X206850Y454033D01*
X206517Y453950D01*
X206267Y453742D01*
X206142Y453367D01*
Y452367D01*
G01X205475Y455283D02*
X205267Y455533D01*
X205142Y455825D01*
X205100Y456200D01*
X205183Y456575D01*
X205350Y456867D01*
X205642Y457075D01*
X205975Y457117D01*
X206308Y457033D01*
X206517Y456825D01*
X206683Y456533D01*
X206725Y456242D01*
X206683Y455950D01*
X206517Y455575D01*
X207600Y455700D01*
Y456825D01*
G01X205100Y459117D02*
X205642Y459200D01*
X206100Y459325D01*
X206517Y459492D01*
X206975Y459700D01*
X207600Y460033D01*
Y458367D01*
G01X165967Y470500D02*
X163467D01*
G01X165967Y469542D02*
Y471458D01*
G01X163467Y472667D02*
X165967D01*
Y473667D01*
X165842Y474000D01*
X165550Y474250D01*
X165217Y474333D01*
X164884Y474250D01*
X164634Y474042D01*
X164509Y473667D01*
Y472667D01*
G01X163842Y475583D02*
X163634Y475833D01*
X163509Y476125D01*
X163467Y476500D01*
X163550Y476875D01*
X163717Y477167D01*
X164009Y477375D01*
X164342Y477417D01*
X164675Y477333D01*
X164884Y477125D01*
X165050Y476833D01*
X165092Y476542D01*
X165050Y476250D01*
X164884Y475875D01*
X165967Y476000D01*
Y477125D01*
G01X163759Y478792D02*
X163550Y479083D01*
X163467Y479417D01*
X163550Y479750D01*
X163800Y480042D01*
X164175Y480250D01*
X164550Y480333D01*
X165009D01*
X165384Y480250D01*
X165717Y480042D01*
X165884Y479792D01*
X165967Y479500D01*
X165884Y479167D01*
X165717Y478917D01*
X165467Y478750D01*
X165134Y478667D01*
X164842Y478750D01*
X164550Y478958D01*
X164384Y479208D01*
X164342Y479500D01*
X164425Y479833D01*
X164634Y480083D01*
X165009Y480333D01*
G01X162575Y456568D02*
Y454068D01*
G01X163533Y456568D02*
X161617D01*
G01X160408Y454068D02*
Y456568D01*
X159408D01*
X159075Y456443D01*
X158825Y456151D01*
X158742Y455818D01*
X158825Y455485D01*
X159033Y455235D01*
X159408Y455110D01*
X160408D01*
G01X157367D02*
X157075Y455401D01*
X156825Y455568D01*
X156492Y455651D01*
X156200Y455568D01*
X155992Y455401D01*
X155825Y455151D01*
X155783Y454860D01*
X155825Y454610D01*
X155992Y454360D01*
X156242Y454151D01*
X156533Y454068D01*
X156867Y454151D01*
X157158Y454401D01*
X157325Y454776D01*
X157367Y455193D01*
X157283Y455735D01*
X157158Y456026D01*
X156950Y456318D01*
X156658Y456526D01*
X156367Y456568D01*
X156075Y456485D01*
X155867Y456276D01*
G01X153575Y456568D02*
X153908Y456485D01*
X154158Y456276D01*
X154325Y456026D01*
X154450Y455693D01*
X154492Y455318D01*
X154450Y454943D01*
X154325Y454610D01*
X154158Y454360D01*
X153908Y454151D01*
X153575Y454068D01*
X153242Y454151D01*
X152992Y454360D01*
X152825Y454610D01*
X152700Y454943D01*
X152658Y455318D01*
X152700Y455693D01*
X152825Y456026D01*
X152992Y456276D01*
X153242Y456485D01*
X153575Y456568D01*
G01X209000Y464500D02*
X206500D01*
G01X209000Y463542D02*
Y465458D01*
G01X206500Y466667D02*
X209000D01*
Y467667D01*
X208875Y468000D01*
X208583Y468250D01*
X208250Y468333D01*
X207917Y468250D01*
X207667Y468042D01*
X207542Y467667D01*
Y466667D01*
G01Y469708D02*
X207833Y470000D01*
X208000Y470250D01*
X208083Y470583D01*
X208000Y470875D01*
X207833Y471083D01*
X207583Y471250D01*
X207292Y471292D01*
X207042Y471250D01*
X206792Y471083D01*
X206583Y470833D01*
X206500Y470542D01*
X206583Y470208D01*
X206833Y469917D01*
X207208Y469750D01*
X207625Y469708D01*
X208167Y469792D01*
X208458Y469917D01*
X208750Y470125D01*
X208958Y470417D01*
X209000Y470708D01*
X208917Y471000D01*
X208708Y471208D01*
G01X208583Y472708D02*
X208833Y472958D01*
X208958Y473250D01*
X209000Y473583D01*
X208917Y474000D01*
X208708Y474292D01*
X208458Y474375D01*
X208208Y474333D01*
X208000Y474167D01*
X207583Y473333D01*
X207292Y472958D01*
X206875Y472708D01*
X206500Y472625D01*
Y474375D01*
G01X168337Y448532D02*
Y446032D01*
G01X169295Y448532D02*
X167379D01*
G01X166170Y446032D02*
Y448532D01*
X165170D01*
X164837Y448407D01*
X164587Y448115D01*
X164504Y447782D01*
X164587Y447449D01*
X164795Y447199D01*
X165170Y447074D01*
X166170D01*
G01X163129D02*
X162837Y447365D01*
X162587Y447532D01*
X162254Y447615D01*
X161962Y447532D01*
X161754Y447365D01*
X161587Y447115D01*
X161545Y446824D01*
X161587Y446574D01*
X161754Y446324D01*
X162004Y446115D01*
X162295Y446032D01*
X162629Y446115D01*
X162920Y446365D01*
X163087Y446740D01*
X163129Y447157D01*
X163045Y447699D01*
X162920Y447990D01*
X162712Y448282D01*
X162420Y448490D01*
X162129Y448532D01*
X161837Y448449D01*
X161629Y448240D01*
G01X160254Y446532D02*
X160004Y446240D01*
X159670Y446074D01*
X159295Y446032D01*
X158962Y446074D01*
X158629Y446282D01*
X158420Y446532D01*
X158379Y446782D01*
X158462Y447074D01*
X158754Y447282D01*
X159045Y447365D01*
X159420D01*
G01X159045D02*
X158795Y447490D01*
X158587Y447699D01*
X158504Y447949D01*
X158587Y448199D01*
X158795Y448407D01*
X159170Y448532D01*
X159545Y448490D01*
X159920Y448324D01*
G01X179711Y437579D02*
Y435079D01*
G01X180669Y437579D02*
X178753D01*
G01X177544Y435079D02*
Y437579D01*
X176544D01*
X176211Y437454D01*
X175961Y437162D01*
X175878Y436829D01*
X175961Y436496D01*
X176169Y436246D01*
X176544Y436121D01*
X177544D01*
G01X174503D02*
X174211Y436412D01*
X173961Y436579D01*
X173628Y436662D01*
X173336Y436579D01*
X173128Y436412D01*
X172961Y436162D01*
X172919Y435871D01*
X172961Y435621D01*
X173128Y435371D01*
X173378Y435162D01*
X173669Y435079D01*
X174003Y435162D01*
X174294Y435412D01*
X174461Y435787D01*
X174503Y436204D01*
X174419Y436746D01*
X174294Y437037D01*
X174086Y437329D01*
X173794Y437537D01*
X173503Y437579D01*
X173211Y437496D01*
X173003Y437287D01*
G01X170711Y435079D02*
X170419Y435121D01*
X170086Y435246D01*
X169878Y435454D01*
X169794Y435746D01*
X169878Y436037D01*
X170128Y436287D01*
X170503Y436412D01*
X170919D01*
X171169Y436496D01*
X171378Y436704D01*
X171461Y436996D01*
X171336Y437287D01*
X171044Y437496D01*
X170711Y437579D01*
X170378Y437496D01*
X170086Y437287D01*
X169961Y436996D01*
X170044Y436704D01*
X170253Y436496D01*
X170503Y436412D01*
X170919D01*
X171294Y436287D01*
X171544Y436037D01*
X171628Y435746D01*
X171544Y435454D01*
X171336Y435246D01*
X171003Y435121D01*
X170711Y435079D01*
G01X160742Y550330D02*
X160867Y550080D01*
X160950Y549788D01*
Y549455D01*
X160825Y549080D01*
X160617Y548788D01*
X160367Y548580D01*
X159950Y548413D01*
X159575Y548371D01*
X159200Y548455D01*
X158950Y548580D01*
X158700Y548830D01*
X158533Y549121D01*
X158450Y549413D01*
Y549705D01*
X158533Y549996D01*
X158658Y550246D01*
X158825Y550455D01*
G01X158450Y552413D02*
X160950D01*
X160450Y551913D01*
G01X158450D02*
Y552913D01*
G01X160533Y554621D02*
X160783Y554871D01*
X160908Y555163D01*
X160950Y555496D01*
X160867Y555913D01*
X160658Y556205D01*
X160408Y556288D01*
X160158Y556246D01*
X159950Y556080D01*
X159533Y555246D01*
X159242Y554871D01*
X158825Y554621D01*
X158450Y554538D01*
Y556288D01*
G01X160533Y557621D02*
X160783Y557871D01*
X160908Y558163D01*
X160950Y558496D01*
X160867Y558913D01*
X160658Y559205D01*
X160408Y559288D01*
X160158Y559246D01*
X159950Y559080D01*
X159533Y558246D01*
X159242Y557871D01*
X158825Y557621D01*
X158450Y557538D01*
Y559288D01*
G01X165194Y521995D02*
X165319Y521745D01*
X165402Y521453D01*
Y521120D01*
X165277Y520745D01*
X165069Y520453D01*
X164819Y520245D01*
X164402Y520078D01*
X164027Y520036D01*
X163652Y520120D01*
X163402Y520245D01*
X163152Y520495D01*
X162985Y520786D01*
X162902Y521078D01*
Y521370D01*
X162985Y521661D01*
X163110Y521911D01*
X163277Y522120D01*
G01X162902Y524078D02*
X165402D01*
X164902Y523578D01*
G01X162902D02*
Y524578D01*
G01Y527078D02*
X165402D01*
X164902Y526578D01*
G01X162902D02*
Y527578D01*
G01X165402Y530078D02*
X165319Y529745D01*
X165110Y529495D01*
X164860Y529328D01*
X164527Y529203D01*
X164152Y529161D01*
X163777Y529203D01*
X163444Y529328D01*
X163194Y529495D01*
X162985Y529745D01*
X162902Y530078D01*
X162985Y530411D01*
X163194Y530661D01*
X163444Y530828D01*
X163777Y530953D01*
X164152Y530995D01*
X164527Y530953D01*
X164860Y530828D01*
X165110Y530661D01*
X165319Y530411D01*
X165402Y530078D01*
G01X170258Y536365D02*
X170508Y536490D01*
X170800Y536573D01*
X171133D01*
X171508Y536448D01*
X171800Y536240D01*
X172008Y535990D01*
X172175Y535573D01*
X172217Y535198D01*
X172133Y534823D01*
X172008Y534573D01*
X171758Y534323D01*
X171467Y534156D01*
X171175Y534073D01*
X170883D01*
X170592Y534156D01*
X170342Y534281D01*
X170133Y534448D01*
G01X168175Y534073D02*
Y536573D01*
X168675Y536073D01*
G01Y534073D02*
X167675D01*
G01X165175D02*
Y536573D01*
X165675Y536073D01*
G01Y534073D02*
X164675D01*
G01X163092Y534573D02*
X162842Y534281D01*
X162508Y534115D01*
X162133Y534073D01*
X161800Y534115D01*
X161467Y534323D01*
X161258Y534573D01*
X161217Y534823D01*
X161300Y535115D01*
X161592Y535323D01*
X161883Y535406D01*
X162258D01*
G01X161883D02*
X161633Y535531D01*
X161425Y535740D01*
X161342Y535990D01*
X161425Y536240D01*
X161633Y536448D01*
X162008Y536573D01*
X162383Y536531D01*
X162758Y536365D01*
G01X158102Y509676D02*
X158227Y509426D01*
X158310Y509134D01*
Y508801D01*
X158185Y508426D01*
X157977Y508134D01*
X157727Y507926D01*
X157310Y507759D01*
X156935Y507717D01*
X156560Y507801D01*
X156310Y507926D01*
X156060Y508176D01*
X155893Y508467D01*
X155810Y508759D01*
Y509051D01*
X155893Y509342D01*
X156018Y509592D01*
X156185Y509801D01*
G01X155810Y511759D02*
X158310D01*
X157810Y511259D01*
G01X155810D02*
Y512259D01*
G01X158310Y514759D02*
X158227Y514426D01*
X158018Y514176D01*
X157768Y514009D01*
X157435Y513884D01*
X157060Y513842D01*
X156685Y513884D01*
X156352Y514009D01*
X156102Y514176D01*
X155893Y514426D01*
X155810Y514759D01*
X155893Y515092D01*
X156102Y515342D01*
X156352Y515509D01*
X156685Y515634D01*
X157060Y515676D01*
X157435Y515634D01*
X157768Y515509D01*
X158018Y515342D01*
X158227Y515092D01*
X158310Y514759D01*
G01X156102Y517051D02*
X155893Y517342D01*
X155810Y517676D01*
X155893Y518009D01*
X156143Y518301D01*
X156518Y518509D01*
X156893Y518592D01*
X157352D01*
X157727Y518509D01*
X158060Y518301D01*
X158227Y518051D01*
X158310Y517759D01*
X158227Y517426D01*
X158060Y517176D01*
X157810Y517009D01*
X157477Y516926D01*
X157185Y517009D01*
X156893Y517217D01*
X156727Y517467D01*
X156685Y517759D01*
X156768Y518092D01*
X156977Y518342D01*
X157352Y518592D01*
G01X160486Y542436D02*
X160736Y542561D01*
X161028Y542644D01*
X161361D01*
X161736Y542519D01*
X162028Y542311D01*
X162236Y542061D01*
X162403Y541644D01*
X162445Y541269D01*
X162361Y540894D01*
X162236Y540644D01*
X161986Y540394D01*
X161695Y540227D01*
X161403Y540144D01*
X161111D01*
X160820Y540227D01*
X160570Y540352D01*
X160361Y540519D01*
G01X159111Y540436D02*
X158820Y540227D01*
X158486Y540144D01*
X158153Y540227D01*
X157861Y540477D01*
X157653Y540852D01*
X157570Y541227D01*
Y541686D01*
X157653Y542061D01*
X157861Y542394D01*
X158111Y542561D01*
X158403Y542644D01*
X158736Y542561D01*
X158986Y542394D01*
X159153Y542144D01*
X159236Y541811D01*
X159153Y541519D01*
X158945Y541227D01*
X158695Y541061D01*
X158403Y541019D01*
X158070Y541102D01*
X157820Y541311D01*
X157570Y541686D01*
G01X156320Y540644D02*
X156070Y540352D01*
X155736Y540186D01*
X155361Y540144D01*
X155028Y540186D01*
X154695Y540394D01*
X154486Y540644D01*
X154445Y540894D01*
X154528Y541186D01*
X154820Y541394D01*
X155111Y541477D01*
X155486D01*
G01X155111D02*
X154861Y541602D01*
X154653Y541811D01*
X154570Y542061D01*
X154653Y542311D01*
X154861Y542519D01*
X155236Y542644D01*
X155611Y542602D01*
X155986Y542436D01*
G01X156439Y531085D02*
X156689Y531210D01*
X156981Y531293D01*
X157314D01*
X157689Y531168D01*
X157981Y530960D01*
X158189Y530710D01*
X158356Y530293D01*
X158398Y529918D01*
X158314Y529543D01*
X158189Y529293D01*
X157939Y529043D01*
X157648Y528876D01*
X157356Y528793D01*
X157064D01*
X156773Y528876D01*
X156523Y529001D01*
X156314Y529168D01*
G01X155064Y529085D02*
X154773Y528876D01*
X154439Y528793D01*
X154106Y528876D01*
X153814Y529126D01*
X153606Y529501D01*
X153523Y529876D01*
Y530335D01*
X153606Y530710D01*
X153814Y531043D01*
X154064Y531210D01*
X154356Y531293D01*
X154689Y531210D01*
X154939Y531043D01*
X155106Y530793D01*
X155189Y530460D01*
X155106Y530168D01*
X154898Y529876D01*
X154648Y529710D01*
X154356Y529668D01*
X154023Y529751D01*
X153773Y529960D01*
X153523Y530335D01*
G01X151356Y528793D02*
Y531293D01*
X151856Y530793D01*
G01Y528793D02*
X150856D01*
G01X156791Y526333D02*
X157041Y526458D01*
X157333Y526541D01*
X157666D01*
X158041Y526416D01*
X158333Y526208D01*
X158541Y525958D01*
X158708Y525541D01*
X158750Y525166D01*
X158666Y524791D01*
X158541Y524541D01*
X158291Y524291D01*
X158000Y524124D01*
X157708Y524041D01*
X157416D01*
X157125Y524124D01*
X156875Y524249D01*
X156666Y524416D01*
G01X155416Y524333D02*
X155125Y524124D01*
X154791Y524041D01*
X154458Y524124D01*
X154166Y524374D01*
X153958Y524749D01*
X153875Y525124D01*
Y525583D01*
X153958Y525958D01*
X154166Y526291D01*
X154416Y526458D01*
X154708Y526541D01*
X155041Y526458D01*
X155291Y526291D01*
X155458Y526041D01*
X155541Y525708D01*
X155458Y525416D01*
X155250Y525124D01*
X155000Y524958D01*
X154708Y524916D01*
X154375Y524999D01*
X154125Y525208D01*
X153875Y525583D01*
G01X151708Y526541D02*
X152041Y526458D01*
X152291Y526249D01*
X152458Y525999D01*
X152583Y525666D01*
X152625Y525291D01*
X152583Y524916D01*
X152458Y524583D01*
X152291Y524333D01*
X152041Y524124D01*
X151708Y524041D01*
X151375Y524124D01*
X151125Y524333D01*
X150958Y524583D01*
X150833Y524916D01*
X150791Y525291D01*
X150833Y525666D01*
X150958Y525999D01*
X151125Y526249D01*
X151375Y526458D01*
X151708Y526541D01*
G01X160310Y546484D02*
X160560Y546609D01*
X160852Y546692D01*
X161185D01*
X161560Y546567D01*
X161852Y546359D01*
X162060Y546109D01*
X162227Y545692D01*
X162269Y545317D01*
X162185Y544942D01*
X162060Y544692D01*
X161810Y544442D01*
X161519Y544275D01*
X161227Y544192D01*
X160935D01*
X160644Y544275D01*
X160394Y544400D01*
X160185Y544567D01*
G01X158227Y544192D02*
X157935Y544234D01*
X157602Y544359D01*
X157394Y544567D01*
X157310Y544859D01*
X157394Y545150D01*
X157644Y545400D01*
X158019Y545525D01*
X158435D01*
X158685Y545609D01*
X158894Y545817D01*
X158977Y546109D01*
X158852Y546400D01*
X158560Y546609D01*
X158227Y546692D01*
X157894Y546609D01*
X157602Y546400D01*
X157477Y546109D01*
X157560Y545817D01*
X157769Y545609D01*
X158019Y545525D01*
X158435D01*
X158810Y545400D01*
X159060Y545150D01*
X159144Y544859D01*
X159060Y544567D01*
X158852Y544359D01*
X158519Y544234D01*
X158227Y544192D01*
G01X155227D02*
X154935Y544234D01*
X154602Y544359D01*
X154394Y544567D01*
X154310Y544859D01*
X154394Y545150D01*
X154644Y545400D01*
X155019Y545525D01*
X155435D01*
X155685Y545609D01*
X155894Y545817D01*
X155977Y546109D01*
X155852Y546400D01*
X155560Y546609D01*
X155227Y546692D01*
X154894Y546609D01*
X154602Y546400D01*
X154477Y546109D01*
X154560Y545817D01*
X154769Y545609D01*
X155019Y545525D01*
X155435D01*
X155810Y545400D01*
X156060Y545150D01*
X156144Y544859D01*
X156060Y544567D01*
X155852Y544359D01*
X155519Y544234D01*
X155227Y544192D01*
G01X155111Y554730D02*
X155236Y554480D01*
X155319Y554188D01*
Y553855D01*
X155194Y553480D01*
X154986Y553188D01*
X154736Y552980D01*
X154319Y552813D01*
X153944Y552771D01*
X153569Y552855D01*
X153319Y552980D01*
X153069Y553230D01*
X152902Y553521D01*
X152819Y553813D01*
Y554105D01*
X152902Y554396D01*
X153027Y554646D01*
X153194Y554855D01*
G01X152819Y556813D02*
X155319D01*
X154819Y556313D01*
G01X152819D02*
Y557313D01*
G01X153319Y558896D02*
X153027Y559146D01*
X152861Y559480D01*
X152819Y559855D01*
X152861Y560188D01*
X153069Y560521D01*
X153319Y560730D01*
X153569Y560771D01*
X153861Y560688D01*
X154069Y560396D01*
X154152Y560105D01*
Y559730D01*
G01Y560105D02*
X154277Y560355D01*
X154486Y560563D01*
X154736Y560646D01*
X154986Y560563D01*
X155194Y560355D01*
X155319Y559980D01*
X155277Y559605D01*
X155111Y559230D01*
G01X152819Y562813D02*
X155319D01*
X154819Y562313D01*
G01X152819D02*
Y563313D01*
G01X153879Y512668D02*
X154004Y512418D01*
X154087Y512126D01*
Y511793D01*
X153962Y511418D01*
X153754Y511126D01*
X153504Y510918D01*
X153087Y510751D01*
X152712Y510709D01*
X152337Y510793D01*
X152087Y510918D01*
X151837Y511168D01*
X151670Y511459D01*
X151587Y511751D01*
Y512043D01*
X151670Y512334D01*
X151795Y512584D01*
X151962Y512793D01*
G01X151587Y514751D02*
X154087D01*
X153587Y514251D01*
G01X151587D02*
Y515251D01*
G01Y518251D02*
X154087D01*
X152295Y516709D01*
Y518793D01*
G01X151587Y520751D02*
X154087D01*
X153587Y520251D01*
G01X151587D02*
Y521251D01*
G01X189700Y499800D02*
Y497300D01*
G01X190658Y499800D02*
X188742D01*
G01X187533Y497300D02*
Y499800D01*
X186533D01*
X186200Y499675D01*
X185950Y499383D01*
X185867Y499050D01*
X185950Y498717D01*
X186158Y498467D01*
X186533Y498342D01*
X187533D01*
G01X183700Y497300D02*
Y499800D01*
X184200Y499300D01*
G01Y497300D02*
X183200D01*
G01X181408Y497592D02*
X181117Y497383D01*
X180783Y497300D01*
X180450Y497383D01*
X180158Y497633D01*
X179950Y498008D01*
X179867Y498383D01*
Y498842D01*
X179950Y499217D01*
X180158Y499550D01*
X180408Y499717D01*
X180700Y499800D01*
X181033Y499717D01*
X181283Y499550D01*
X181450Y499300D01*
X181533Y498967D01*
X181450Y498675D01*
X181242Y498383D01*
X180992Y498217D01*
X180700Y498175D01*
X180367Y498258D01*
X180117Y498467D01*
X179867Y498842D01*
G01X189400Y495300D02*
Y492800D01*
G01X190358Y495300D02*
X188442D01*
G01X187233Y492800D02*
Y495300D01*
X186233D01*
X185900Y495175D01*
X185650Y494883D01*
X185567Y494550D01*
X185650Y494217D01*
X185858Y493967D01*
X186233Y493842D01*
X187233D01*
G01X184192Y494883D02*
X183942Y495133D01*
X183650Y495258D01*
X183317Y495300D01*
X182900Y495217D01*
X182608Y495008D01*
X182525Y494758D01*
X182567Y494508D01*
X182733Y494300D01*
X183567Y493883D01*
X183942Y493592D01*
X184192Y493175D01*
X184275Y492800D01*
X182525D01*
G01X180400Y495300D02*
X180733Y495217D01*
X180983Y495008D01*
X181150Y494758D01*
X181275Y494425D01*
X181317Y494050D01*
X181275Y493675D01*
X181150Y493342D01*
X180983Y493092D01*
X180733Y492883D01*
X180400Y492800D01*
X180067Y492883D01*
X179817Y493092D01*
X179650Y493342D01*
X179525Y493675D01*
X179483Y494050D01*
X179525Y494425D01*
X179650Y494758D01*
X179817Y495008D01*
X180067Y495217D01*
X180400Y495300D01*
G01X190100Y508500D02*
Y506000D01*
G01X191058Y508500D02*
X189142D01*
G01X187933Y506000D02*
Y508500D01*
X186933D01*
X186600Y508375D01*
X186350Y508083D01*
X186267Y507750D01*
X186350Y507417D01*
X186558Y507167D01*
X186933Y507042D01*
X187933D01*
G01X184892Y508083D02*
X184642Y508333D01*
X184350Y508458D01*
X184017Y508500D01*
X183600Y508417D01*
X183308Y508208D01*
X183225Y507958D01*
X183267Y507708D01*
X183433Y507500D01*
X184267Y507083D01*
X184642Y506792D01*
X184892Y506375D01*
X184975Y506000D01*
X183225D01*
G01X182017Y506500D02*
X181767Y506208D01*
X181433Y506042D01*
X181058Y506000D01*
X180725Y506042D01*
X180392Y506250D01*
X180183Y506500D01*
X180142Y506750D01*
X180225Y507042D01*
X180517Y507250D01*
X180808Y507333D01*
X181183D01*
G01X180808D02*
X180558Y507458D01*
X180350Y507667D01*
X180267Y507917D01*
X180350Y508167D01*
X180558Y508375D01*
X180933Y508500D01*
X181308Y508458D01*
X181683Y508292D01*
G01X165632Y500759D02*
Y498259D01*
G01X166590Y500759D02*
X164674D01*
G01X163465Y498259D02*
Y500759D01*
X162465D01*
X162132Y500634D01*
X161882Y500342D01*
X161799Y500009D01*
X161882Y499676D01*
X162090Y499426D01*
X162465Y499301D01*
X163465D01*
G01X160549Y498634D02*
X160299Y498426D01*
X160007Y498301D01*
X159632Y498259D01*
X159257Y498342D01*
X158965Y498509D01*
X158757Y498801D01*
X158715Y499134D01*
X158799Y499467D01*
X159007Y499676D01*
X159299Y499842D01*
X159590Y499884D01*
X159882Y499842D01*
X160257Y499676D01*
X160132Y500759D01*
X159007D01*
G01X157424Y500342D02*
X157174Y500592D01*
X156882Y500717D01*
X156549Y500759D01*
X156132Y500676D01*
X155840Y500467D01*
X155757Y500217D01*
X155799Y499967D01*
X155965Y499759D01*
X156799Y499342D01*
X157174Y499051D01*
X157424Y498634D01*
X157507Y498259D01*
X155757D01*
G01X193700Y490500D02*
Y488000D01*
G01X194658Y490500D02*
X192742D01*
G01X191533Y488000D02*
Y490500D01*
X190533D01*
X190200Y490375D01*
X189950Y490083D01*
X189867Y489750D01*
X189950Y489417D01*
X190158Y489167D01*
X190533Y489042D01*
X191533D01*
G01X188617Y488375D02*
X188367Y488167D01*
X188075Y488042D01*
X187700Y488000D01*
X187325Y488083D01*
X187033Y488250D01*
X186825Y488542D01*
X186783Y488875D01*
X186867Y489208D01*
X187075Y489417D01*
X187367Y489583D01*
X187658Y489625D01*
X187950Y489583D01*
X188325Y489417D01*
X188200Y490500D01*
X187075D01*
G01X184700Y488000D02*
X184408Y488042D01*
X184075Y488167D01*
X183867Y488375D01*
X183783Y488667D01*
X183867Y488958D01*
X184117Y489208D01*
X184492Y489333D01*
X184908D01*
X185158Y489417D01*
X185367Y489625D01*
X185450Y489917D01*
X185325Y490208D01*
X185033Y490417D01*
X184700Y490500D01*
X184367Y490417D01*
X184075Y490208D01*
X183950Y489917D01*
X184033Y489625D01*
X184242Y489417D01*
X184492Y489333D01*
X184908D01*
X185283Y489208D01*
X185533Y488958D01*
X185617Y488667D01*
X185533Y488375D01*
X185325Y488167D01*
X184992Y488042D01*
X184700Y488000D01*
G01X189500Y504600D02*
Y502100D01*
G01X190458Y504600D02*
X188542D01*
G01X187333Y502100D02*
Y504600D01*
X186333D01*
X186000Y504475D01*
X185750Y504183D01*
X185667Y503850D01*
X185750Y503517D01*
X185958Y503267D01*
X186333Y503142D01*
X187333D01*
G01X184292D02*
X184000Y503433D01*
X183750Y503600D01*
X183417Y503683D01*
X183125Y503600D01*
X182917Y503433D01*
X182750Y503183D01*
X182708Y502892D01*
X182750Y502642D01*
X182917Y502392D01*
X183167Y502183D01*
X183458Y502100D01*
X183792Y502183D01*
X184083Y502433D01*
X184250Y502808D01*
X184292Y503225D01*
X184208Y503767D01*
X184083Y504058D01*
X183875Y504350D01*
X183583Y504558D01*
X183292Y504600D01*
X183000Y504517D01*
X182792Y504308D01*
G01X180500Y502100D02*
Y504600D01*
X181000Y504100D01*
G01Y502100D02*
X180000D01*
G01X171865Y818732D02*
X172115Y818857D01*
X172407Y818940D01*
X172740D01*
X173115Y818815D01*
X173407Y818607D01*
X173615Y818357D01*
X173782Y817940D01*
X173824Y817565D01*
X173740Y817190D01*
X173615Y816940D01*
X173365Y816690D01*
X173074Y816523D01*
X172782Y816440D01*
X172490D01*
X172199Y816523D01*
X171949Y816648D01*
X171740Y816815D01*
G01X169782Y816440D02*
Y818940D01*
X170282Y818440D01*
G01Y816440D02*
X169282D01*
G01X166782D02*
X166490Y816482D01*
X166157Y816607D01*
X165949Y816815D01*
X165865Y817107D01*
X165949Y817398D01*
X166199Y817648D01*
X166574Y817773D01*
X166990D01*
X167240Y817857D01*
X167449Y818065D01*
X167532Y818357D01*
X167407Y818648D01*
X167115Y818857D01*
X166782Y818940D01*
X166449Y818857D01*
X166157Y818648D01*
X166032Y818357D01*
X166115Y818065D01*
X166324Y817857D01*
X166574Y817773D01*
X166990D01*
X167365Y817648D01*
X167615Y817398D01*
X167699Y817107D01*
X167615Y816815D01*
X167407Y816607D01*
X167074Y816482D01*
X166782Y816440D01*
G01X163282D02*
Y818940D01*
X164824Y817148D01*
X162740D01*
G01X171865Y814732D02*
X172115Y814857D01*
X172407Y814940D01*
X172740D01*
X173115Y814815D01*
X173407Y814607D01*
X173615Y814357D01*
X173782Y813940D01*
X173824Y813565D01*
X173740Y813190D01*
X173615Y812940D01*
X173365Y812690D01*
X173074Y812523D01*
X172782Y812440D01*
X172490D01*
X172199Y812523D01*
X171949Y812648D01*
X171740Y812815D01*
G01X169782Y812440D02*
Y814940D01*
X170282Y814440D01*
G01Y812440D02*
X169282D01*
G01X166782D02*
X166490Y812482D01*
X166157Y812607D01*
X165949Y812815D01*
X165865Y813107D01*
X165949Y813398D01*
X166199Y813648D01*
X166574Y813773D01*
X166990D01*
X167240Y813857D01*
X167449Y814065D01*
X167532Y814357D01*
X167407Y814648D01*
X167115Y814857D01*
X166782Y814940D01*
X166449Y814857D01*
X166157Y814648D01*
X166032Y814357D01*
X166115Y814065D01*
X166324Y813857D01*
X166574Y813773D01*
X166990D01*
X167365Y813648D01*
X167615Y813398D01*
X167699Y813107D01*
X167615Y812815D01*
X167407Y812607D01*
X167074Y812482D01*
X166782Y812440D01*
G01X164699Y812815D02*
X164449Y812607D01*
X164157Y812482D01*
X163782Y812440D01*
X163407Y812523D01*
X163115Y812690D01*
X162907Y812982D01*
X162865Y813315D01*
X162949Y813648D01*
X163157Y813857D01*
X163449Y814023D01*
X163740Y814065D01*
X164032Y814023D01*
X164407Y813857D01*
X164282Y814940D01*
X163157D01*
G01X251533Y480400D02*
Y482900D01*
X250492D01*
X250158Y482775D01*
X249950Y482608D01*
X249867Y482275D01*
X249950Y481942D01*
X250200Y481733D01*
X250492Y481608D01*
X251533D01*
G01X250492D02*
X249867Y480400D01*
G01X247700D02*
Y482900D01*
X248200Y482400D01*
G01Y480400D02*
X247200D01*
G01X245492Y482483D02*
X245242Y482733D01*
X244950Y482858D01*
X244617Y482900D01*
X244200Y482817D01*
X243908Y482608D01*
X243825Y482358D01*
X243867Y482108D01*
X244033Y481900D01*
X244867Y481483D01*
X245242Y481192D01*
X245492Y480775D01*
X245575Y480400D01*
X243825D01*
G01X242408Y480692D02*
X242117Y480483D01*
X241783Y480400D01*
X241450Y480483D01*
X241158Y480733D01*
X240950Y481108D01*
X240867Y481483D01*
Y481942D01*
X240950Y482317D01*
X241158Y482650D01*
X241408Y482817D01*
X241700Y482900D01*
X242033Y482817D01*
X242283Y482650D01*
X242450Y482400D01*
X242533Y482067D01*
X242450Y481775D01*
X242242Y481483D01*
X241992Y481317D01*
X241700Y481275D01*
X241367Y481358D01*
X241117Y481567D01*
X240867Y481942D01*
G01X251433Y476100D02*
Y478600D01*
X250392D01*
X250058Y478475D01*
X249850Y478308D01*
X249767Y477975D01*
X249850Y477642D01*
X250100Y477433D01*
X250392Y477308D01*
X251433D01*
G01X250392D02*
X249767Y476100D01*
G01X247600D02*
Y478600D01*
X248100Y478100D01*
G01Y476100D02*
X247100D01*
G01X244600D02*
Y478600D01*
X245100Y478100D01*
G01Y476100D02*
X244100D01*
G01X241100D02*
Y478600D01*
X242642Y476808D01*
X240558D01*
G01X236133Y468300D02*
Y470800D01*
X235092D01*
X234758Y470675D01*
X234550Y470508D01*
X234467Y470175D01*
X234550Y469842D01*
X234800Y469633D01*
X235092Y469508D01*
X236133D01*
G01X235092D02*
X234467Y468300D01*
G01X232300D02*
Y470800D01*
X232800Y470300D01*
G01Y468300D02*
X231800D01*
G01X229300D02*
Y470800D01*
X229800Y470300D01*
G01Y468300D02*
X228800D01*
G01X227092Y470383D02*
X226842Y470633D01*
X226550Y470758D01*
X226217Y470800D01*
X225800Y470717D01*
X225508Y470508D01*
X225425Y470258D01*
X225467Y470008D01*
X225633Y469800D01*
X226467Y469383D01*
X226842Y469092D01*
X227092Y468675D01*
X227175Y468300D01*
X225425D01*
G01X408885Y426972D02*
X411385D01*
Y427972D01*
X411260Y428305D01*
X410968Y428555D01*
X410635Y428638D01*
X410302Y428555D01*
X410052Y428347D01*
X409927Y427972D01*
Y426972D01*
G01X411385Y429888D02*
X409593D01*
X409218Y430055D01*
X408968Y430388D01*
X408885Y430805D01*
X408968Y431222D01*
X409218Y431555D01*
X409593Y431722D01*
X411385D01*
G01X410968Y433013D02*
X411218Y433263D01*
X411343Y433555D01*
X411385Y433888D01*
X411302Y434305D01*
X411093Y434597D01*
X410843Y434680D01*
X410593Y434638D01*
X410385Y434472D01*
X409968Y433638D01*
X409677Y433263D01*
X409260Y433013D01*
X408885Y432930D01*
Y434680D01*
G01X408444Y469992D02*
Y472492D01*
X407444D01*
X407111Y472367D01*
X406861Y472075D01*
X406778Y471742D01*
X406861Y471409D01*
X407069Y471159D01*
X407444Y471034D01*
X408444D01*
G01X405444Y469992D02*
Y472492D01*
X404403D01*
X404069Y472367D01*
X403861Y472200D01*
X403778Y471867D01*
X403861Y471534D01*
X404111Y471325D01*
X404403Y471200D01*
X405444D01*
G01X404403D02*
X403778Y469992D01*
G01X401611D02*
Y472492D01*
X402111Y471992D01*
G01Y469992D02*
X401111D01*
G01X399528Y470367D02*
X399278Y470159D01*
X398986Y470034D01*
X398611Y469992D01*
X398236Y470075D01*
X397944Y470242D01*
X397736Y470534D01*
X397694Y470867D01*
X397778Y471200D01*
X397986Y471409D01*
X398278Y471575D01*
X398569Y471617D01*
X398861Y471575D01*
X399236Y471409D01*
X399111Y472492D01*
X397986D01*
G01X415915Y426412D02*
X418415D01*
Y427412D01*
X418290Y427745D01*
X417998Y427995D01*
X417665Y428078D01*
X417332Y427995D01*
X417082Y427787D01*
X416957Y427412D01*
Y426412D01*
G01X415915Y429412D02*
X418415D01*
Y430453D01*
X418290Y430787D01*
X418123Y430995D01*
X417790Y431078D01*
X417457Y430995D01*
X417248Y430745D01*
X417123Y430453D01*
Y429412D01*
G01Y430453D02*
X415915Y431078D01*
G01Y433245D02*
X418415D01*
X417915Y432745D01*
G01X415915D02*
Y433745D01*
G01Y436245D02*
X418415D01*
X417915Y435745D01*
G01X415915D02*
Y436745D01*
G01X408444Y474132D02*
Y476632D01*
X407444D01*
X407111Y476507D01*
X406861Y476215D01*
X406778Y475882D01*
X406861Y475549D01*
X407069Y475299D01*
X407444Y475174D01*
X408444D01*
G01X405444Y474132D02*
Y476632D01*
X404403D01*
X404069Y476507D01*
X403861Y476340D01*
X403778Y476007D01*
X403861Y475674D01*
X404111Y475465D01*
X404403Y475340D01*
X405444D01*
G01X404403D02*
X403778Y474132D01*
G01X401611D02*
Y476632D01*
X402111Y476132D01*
G01Y474132D02*
X401111D01*
G01X398611Y476632D02*
X398944Y476549D01*
X399194Y476340D01*
X399361Y476090D01*
X399486Y475757D01*
X399528Y475382D01*
X399486Y475007D01*
X399361Y474674D01*
X399194Y474424D01*
X398944Y474215D01*
X398611Y474132D01*
X398278Y474215D01*
X398028Y474424D01*
X397861Y474674D01*
X397736Y475007D01*
X397694Y475382D01*
X397736Y475757D01*
X397861Y476090D01*
X398028Y476340D01*
X398278Y476549D01*
X398611Y476632D01*
G01X395200Y432067D02*
X397700D01*
Y433067D01*
X397575Y433400D01*
X397283Y433650D01*
X396950Y433733D01*
X396617Y433650D01*
X396367Y433442D01*
X396242Y433067D01*
Y432067D01*
G01X397492Y436817D02*
X397617Y436567D01*
X397700Y436275D01*
Y435942D01*
X397575Y435567D01*
X397367Y435275D01*
X397117Y435067D01*
X396700Y434900D01*
X396325Y434858D01*
X395950Y434942D01*
X395700Y435067D01*
X395450Y435317D01*
X395283Y435608D01*
X395200Y435900D01*
Y436192D01*
X395283Y436483D01*
X395408Y436733D01*
X395575Y436942D01*
G01X395492Y438192D02*
X395283Y438483D01*
X395200Y438817D01*
X395283Y439150D01*
X395533Y439442D01*
X395908Y439650D01*
X396283Y439733D01*
X396742D01*
X397117Y439650D01*
X397450Y439442D01*
X397617Y439192D01*
X397700Y438900D01*
X397617Y438567D01*
X397450Y438317D01*
X397200Y438150D01*
X396867Y438067D01*
X396575Y438150D01*
X396283Y438358D01*
X396117Y438608D01*
X396075Y438900D01*
X396158Y439233D01*
X396367Y439483D01*
X396742Y439733D01*
G01X390600Y431567D02*
X393100D01*
Y432567D01*
X392975Y432900D01*
X392683Y433150D01*
X392350Y433233D01*
X392017Y433150D01*
X391767Y432942D01*
X391642Y432567D01*
Y431567D01*
G01X392892Y436317D02*
X393017Y436067D01*
X393100Y435775D01*
Y435442D01*
X392975Y435067D01*
X392767Y434775D01*
X392517Y434567D01*
X392100Y434400D01*
X391725Y434358D01*
X391350Y434442D01*
X391100Y434567D01*
X390850Y434817D01*
X390683Y435108D01*
X390600Y435400D01*
Y435692D01*
X390683Y435983D01*
X390808Y436233D01*
X390975Y436442D01*
G01X390600Y438400D02*
X393100D01*
X392600Y437900D01*
G01X390600D02*
Y438900D01*
G01X393100Y441400D02*
X393017Y441067D01*
X392808Y440817D01*
X392558Y440650D01*
X392225Y440525D01*
X391850Y440483D01*
X391475Y440525D01*
X391142Y440650D01*
X390892Y440817D01*
X390683Y441067D01*
X390600Y441400D01*
X390683Y441733D01*
X390892Y441983D01*
X391142Y442150D01*
X391475Y442275D01*
X391850Y442317D01*
X392225Y442275D01*
X392558Y442150D01*
X392808Y441983D01*
X393017Y441733D01*
X393100Y441400D01*
G01X376000Y443667D02*
X378500D01*
Y444667D01*
X378375Y445000D01*
X378083Y445250D01*
X377750Y445333D01*
X377417Y445250D01*
X377167Y445042D01*
X377042Y444667D01*
Y443667D01*
G01X376000Y446667D02*
X378500D01*
Y447708D01*
X378375Y448042D01*
X378208Y448250D01*
X377875Y448333D01*
X377542Y448250D01*
X377333Y448000D01*
X377208Y447708D01*
Y446667D01*
G01Y447708D02*
X376000Y448333D01*
G01X376375Y449583D02*
X376167Y449833D01*
X376042Y450125D01*
X376000Y450500D01*
X376083Y450875D01*
X376250Y451167D01*
X376542Y451375D01*
X376875Y451417D01*
X377208Y451333D01*
X377417Y451125D01*
X377583Y450833D01*
X377625Y450542D01*
X377583Y450250D01*
X377417Y449875D01*
X378500Y450000D01*
Y451125D01*
G01X376292Y452792D02*
X376083Y453083D01*
X376000Y453417D01*
X376083Y453750D01*
X376333Y454042D01*
X376708Y454250D01*
X377083Y454333D01*
X377542D01*
X377917Y454250D01*
X378250Y454042D01*
X378417Y453792D01*
X378500Y453500D01*
X378417Y453167D01*
X378250Y452917D01*
X378000Y452750D01*
X377667Y452667D01*
X377375Y452750D01*
X377083Y452958D01*
X376917Y453208D01*
X376875Y453500D01*
X376958Y453833D01*
X377167Y454083D01*
X377542Y454333D01*
G01X429833Y488000D02*
Y490500D01*
X428833D01*
X428500Y490375D01*
X428250Y490083D01*
X428167Y489750D01*
X428250Y489417D01*
X428458Y489167D01*
X428833Y489042D01*
X429833D01*
G01X426833Y488000D02*
Y490500D01*
X425792D01*
X425458Y490375D01*
X425250Y490208D01*
X425167Y489875D01*
X425250Y489542D01*
X425500Y489333D01*
X425792Y489208D01*
X426833D01*
G01X425792D02*
X425167Y488000D01*
G01X423917Y488375D02*
X423667Y488167D01*
X423375Y488042D01*
X423000Y488000D01*
X422625Y488083D01*
X422333Y488250D01*
X422125Y488542D01*
X422083Y488875D01*
X422167Y489208D01*
X422375Y489417D01*
X422667Y489583D01*
X422958Y489625D01*
X423250Y489583D01*
X423625Y489417D01*
X423500Y490500D01*
X422375D01*
G01X420000Y488000D02*
X419708Y488042D01*
X419375Y488167D01*
X419167Y488375D01*
X419083Y488667D01*
X419167Y488958D01*
X419417Y489208D01*
X419792Y489333D01*
X420208D01*
X420458Y489417D01*
X420667Y489625D01*
X420750Y489917D01*
X420625Y490208D01*
X420333Y490417D01*
X420000Y490500D01*
X419667Y490417D01*
X419375Y490208D01*
X419250Y489917D01*
X419333Y489625D01*
X419542Y489417D01*
X419792Y489333D01*
X420208D01*
X420583Y489208D01*
X420833Y488958D01*
X420917Y488667D01*
X420833Y488375D01*
X420625Y488167D01*
X420292Y488042D01*
X420000Y488000D01*
G01X450044Y453272D02*
Y455772D01*
X449044D01*
X448711Y455647D01*
X448461Y455355D01*
X448378Y455022D01*
X448461Y454689D01*
X448669Y454439D01*
X449044Y454314D01*
X450044D01*
G01X445294Y455564D02*
X445544Y455689D01*
X445836Y455772D01*
X446169D01*
X446544Y455647D01*
X446836Y455439D01*
X447044Y455189D01*
X447211Y454772D01*
X447253Y454397D01*
X447169Y454022D01*
X447044Y453772D01*
X446794Y453522D01*
X446503Y453355D01*
X446211Y453272D01*
X445919D01*
X445628Y453355D01*
X445378Y453480D01*
X445169Y453647D01*
G01X443211Y453272D02*
Y455772D01*
X443711Y455272D01*
G01Y453272D02*
X442711D01*
G01X440211D02*
Y455772D01*
X440711Y455272D01*
G01Y453272D02*
X439711D01*
G01X450333Y447393D02*
Y449893D01*
X449333D01*
X449000Y449768D01*
X448750Y449476D01*
X448667Y449143D01*
X448750Y448810D01*
X448958Y448560D01*
X449333Y448435D01*
X450333D01*
G01X445583Y449685D02*
X445833Y449810D01*
X446125Y449893D01*
X446458D01*
X446833Y449768D01*
X447125Y449560D01*
X447333Y449310D01*
X447500Y448893D01*
X447542Y448518D01*
X447458Y448143D01*
X447333Y447893D01*
X447083Y447643D01*
X446792Y447476D01*
X446500Y447393D01*
X446208D01*
X445917Y447476D01*
X445667Y447601D01*
X445458Y447768D01*
G01X443000Y447393D02*
Y449893D01*
X444542Y448101D01*
X442458D01*
G01X441292Y448435D02*
X441000Y448726D01*
X440750Y448893D01*
X440417Y448976D01*
X440125Y448893D01*
X439917Y448726D01*
X439750Y448476D01*
X439708Y448185D01*
X439750Y447935D01*
X439917Y447685D01*
X440167Y447476D01*
X440458Y447393D01*
X440792Y447476D01*
X441083Y447726D01*
X441250Y448101D01*
X441292Y448518D01*
X441208Y449060D01*
X441083Y449351D01*
X440875Y449643D01*
X440583Y449851D01*
X440292Y449893D01*
X440000Y449810D01*
X439792Y449601D01*
G01X431400Y418667D02*
X433900D01*
Y419667D01*
X433775Y420000D01*
X433483Y420250D01*
X433150Y420333D01*
X432817Y420250D01*
X432567Y420042D01*
X432442Y419667D01*
Y418667D01*
G01X431400Y421667D02*
X433900D01*
Y422708D01*
X433775Y423042D01*
X433608Y423250D01*
X433275Y423333D01*
X432942Y423250D01*
X432733Y423000D01*
X432608Y422708D01*
Y421667D01*
G01Y422708D02*
X431400Y423333D01*
G01Y425500D02*
X433900D01*
X433400Y425000D01*
G01X431400D02*
Y426000D01*
G01X431900Y427583D02*
X431608Y427833D01*
X431442Y428167D01*
X431400Y428542D01*
X431442Y428875D01*
X431650Y429208D01*
X431900Y429417D01*
X432150Y429458D01*
X432442Y429375D01*
X432650Y429083D01*
X432733Y428792D01*
Y428417D01*
G01Y428792D02*
X432858Y429042D01*
X433067Y429250D01*
X433317Y429333D01*
X433567Y429250D01*
X433775Y429042D01*
X433900Y428667D01*
X433858Y428292D01*
X433692Y427917D01*
G01X445133Y468400D02*
Y470900D01*
X444133D01*
X443800Y470775D01*
X443550Y470483D01*
X443467Y470150D01*
X443550Y469817D01*
X443758Y469567D01*
X444133Y469442D01*
X445133D01*
G01X442133Y468400D02*
Y470900D01*
X441092D01*
X440758Y470775D01*
X440550Y470608D01*
X440467Y470275D01*
X440550Y469942D01*
X440800Y469733D01*
X441092Y469608D01*
X442133D01*
G01X441092D02*
X440467Y468400D01*
G01X439092Y470483D02*
X438842Y470733D01*
X438550Y470858D01*
X438217Y470900D01*
X437800Y470817D01*
X437508Y470608D01*
X437425Y470358D01*
X437467Y470108D01*
X437633Y469900D01*
X438467Y469483D01*
X438842Y469192D01*
X439092Y468775D01*
X439175Y468400D01*
X437425D01*
G01X434800D02*
Y470900D01*
X436342Y469108D01*
X434258D01*
G01X649483Y532892D02*
X649733Y533017D01*
X650025Y533100D01*
X650358D01*
X650733Y532975D01*
X651025Y532767D01*
X651233Y532517D01*
X651400Y532100D01*
X651442Y531725D01*
X651358Y531350D01*
X651233Y531100D01*
X650983Y530850D01*
X650692Y530683D01*
X650400Y530600D01*
X650108D01*
X649817Y530683D01*
X649567Y530808D01*
X649358Y530975D01*
G01X648192Y532683D02*
X647942Y532933D01*
X647650Y533058D01*
X647317Y533100D01*
X646900Y533017D01*
X646608Y532808D01*
X646525Y532558D01*
X646567Y532308D01*
X646733Y532100D01*
X647567Y531683D01*
X647942Y531392D01*
X648192Y530975D01*
X648275Y530600D01*
X646525D01*
G01X645317Y531100D02*
X645067Y530808D01*
X644733Y530642D01*
X644358Y530600D01*
X644025Y530642D01*
X643692Y530850D01*
X643483Y531100D01*
X643442Y531350D01*
X643525Y531642D01*
X643817Y531850D01*
X644108Y531933D01*
X644483D01*
G01X644108D02*
X643858Y532058D01*
X643650Y532267D01*
X643567Y532517D01*
X643650Y532767D01*
X643858Y532975D01*
X644233Y533100D01*
X644608Y533058D01*
X644983Y532892D01*
G01X642192Y532683D02*
X641942Y532933D01*
X641650Y533058D01*
X641317Y533100D01*
X640900Y533017D01*
X640608Y532808D01*
X640525Y532558D01*
X640567Y532308D01*
X640733Y532100D01*
X641567Y531683D01*
X641942Y531392D01*
X642192Y530975D01*
X642275Y530600D01*
X640525D01*
G01X644083Y536792D02*
X644333Y536917D01*
X644625Y537000D01*
X644958D01*
X645333Y536875D01*
X645625Y536667D01*
X645833Y536417D01*
X646000Y536000D01*
X646042Y535625D01*
X645958Y535250D01*
X645833Y535000D01*
X645583Y534750D01*
X645292Y534583D01*
X645000Y534500D01*
X644708D01*
X644417Y534583D01*
X644167Y534708D01*
X643958Y534875D01*
G01X642792Y536583D02*
X642542Y536833D01*
X642250Y536958D01*
X641917Y537000D01*
X641500Y536917D01*
X641208Y536708D01*
X641125Y536458D01*
X641167Y536208D01*
X641333Y536000D01*
X642167Y535583D01*
X642542Y535292D01*
X642792Y534875D01*
X642875Y534500D01*
X641125D01*
G01X639917Y535000D02*
X639667Y534708D01*
X639333Y534542D01*
X638958Y534500D01*
X638625Y534542D01*
X638292Y534750D01*
X638083Y535000D01*
X638042Y535250D01*
X638125Y535542D01*
X638417Y535750D01*
X638708Y535833D01*
X639083D01*
G01X638708D02*
X638458Y535958D01*
X638250Y536167D01*
X638167Y536417D01*
X638250Y536667D01*
X638458Y536875D01*
X638833Y537000D01*
X639208Y536958D01*
X639583Y536792D01*
G01X636000Y534500D02*
Y537000D01*
X636500Y536500D01*
G01Y534500D02*
X635500D01*
G01X645033Y542600D02*
Y545100D01*
X643992D01*
X643658Y544975D01*
X643450Y544808D01*
X643367Y544475D01*
X643450Y544142D01*
X643700Y543933D01*
X643992Y543808D01*
X645033D01*
G01X643992D02*
X643367Y542600D01*
G01X640700D02*
Y545100D01*
X642242Y543308D01*
X640158D01*
G01X638992Y543642D02*
X638700Y543933D01*
X638450Y544100D01*
X638117Y544183D01*
X637825Y544100D01*
X637617Y543933D01*
X637450Y543683D01*
X637408Y543392D01*
X637450Y543142D01*
X637617Y542892D01*
X637867Y542683D01*
X638158Y542600D01*
X638492Y542683D01*
X638783Y542933D01*
X638950Y543308D01*
X638992Y543725D01*
X638908Y544267D01*
X638783Y544558D01*
X638575Y544850D01*
X638283Y545058D01*
X637992Y545100D01*
X637700Y545017D01*
X637492Y544808D01*
G01X644033Y557500D02*
Y560000D01*
X642992D01*
X642658Y559875D01*
X642450Y559708D01*
X642367Y559375D01*
X642450Y559042D01*
X642700Y558833D01*
X642992Y558708D01*
X644033D01*
G01X642992D02*
X642367Y557500D01*
G01X639700D02*
Y560000D01*
X641242Y558208D01*
X639158D01*
G01X637283Y557500D02*
X637200Y558042D01*
X637075Y558500D01*
X636908Y558917D01*
X636700Y559375D01*
X636367Y560000D01*
X638033D01*
G01X711917Y461167D02*
Y459375D01*
X711750Y459000D01*
X711417Y458750D01*
X711000Y458667D01*
X710583Y458750D01*
X710250Y459000D01*
X710083Y459375D01*
Y461167D01*
G01X707500Y458667D02*
Y461167D01*
X709042Y459375D01*
X706958D01*
G01X679683Y472394D02*
X679933Y472519D01*
X680225Y472602D01*
X680558D01*
X680933Y472477D01*
X681225Y472269D01*
X681433Y472019D01*
X681600Y471602D01*
X681642Y471227D01*
X681558Y470852D01*
X681433Y470602D01*
X681183Y470352D01*
X680892Y470185D01*
X680600Y470102D01*
X680308D01*
X680017Y470185D01*
X679767Y470310D01*
X679558Y470477D01*
G01X678392Y472185D02*
X678142Y472435D01*
X677850Y472560D01*
X677517Y472602D01*
X677100Y472519D01*
X676808Y472310D01*
X676725Y472060D01*
X676767Y471810D01*
X676933Y471602D01*
X677767Y471185D01*
X678142Y470894D01*
X678392Y470477D01*
X678475Y470102D01*
X676725D01*
G01X674600Y472602D02*
X674933Y472519D01*
X675183Y472310D01*
X675350Y472060D01*
X675475Y471727D01*
X675517Y471352D01*
X675475Y470977D01*
X675350Y470644D01*
X675183Y470394D01*
X674933Y470185D01*
X674600Y470102D01*
X674267Y470185D01*
X674017Y470394D01*
X673850Y470644D01*
X673725Y470977D01*
X673683Y471352D01*
X673725Y471727D01*
X673850Y472060D01*
X674017Y472310D01*
X674267Y472519D01*
X674600Y472602D01*
G01X672517Y470477D02*
X672267Y470269D01*
X671975Y470144D01*
X671600Y470102D01*
X671225Y470185D01*
X670933Y470352D01*
X670725Y470644D01*
X670683Y470977D01*
X670767Y471310D01*
X670975Y471519D01*
X671267Y471685D01*
X671558Y471727D01*
X671850Y471685D01*
X672225Y471519D01*
X672100Y472602D01*
X670975D01*
G01X678183Y461292D02*
X678433Y461417D01*
X678725Y461500D01*
X679058D01*
X679433Y461375D01*
X679725Y461167D01*
X679933Y460917D01*
X680100Y460500D01*
X680142Y460125D01*
X680058Y459750D01*
X679933Y459500D01*
X679683Y459250D01*
X679392Y459083D01*
X679100Y459000D01*
X678808D01*
X678517Y459083D01*
X678267Y459208D01*
X678058Y459375D01*
G01X676892Y461083D02*
X676642Y461333D01*
X676350Y461458D01*
X676017Y461500D01*
X675600Y461417D01*
X675308Y461208D01*
X675225Y460958D01*
X675267Y460708D01*
X675433Y460500D01*
X676267Y460083D01*
X676642Y459792D01*
X676892Y459375D01*
X676975Y459000D01*
X675225D01*
G01X673100D02*
Y461500D01*
X673600Y461000D01*
G01Y459000D02*
X672600D01*
G01X670892Y461083D02*
X670642Y461333D01*
X670350Y461458D01*
X670017Y461500D01*
X669600Y461417D01*
X669308Y461208D01*
X669225Y460958D01*
X669267Y460708D01*
X669433Y460500D01*
X670267Y460083D01*
X670642Y459792D01*
X670892Y459375D01*
X670975Y459000D01*
X669225D01*
G01X672883Y450892D02*
X673133Y451017D01*
X673425Y451100D01*
X673758D01*
X674133Y450975D01*
X674425Y450767D01*
X674633Y450517D01*
X674800Y450100D01*
X674842Y449725D01*
X674758Y449350D01*
X674633Y449100D01*
X674383Y448850D01*
X674092Y448683D01*
X673800Y448600D01*
X673508D01*
X673217Y448683D01*
X672967Y448808D01*
X672758Y448975D01*
G01X671592Y450683D02*
X671342Y450933D01*
X671050Y451058D01*
X670717Y451100D01*
X670300Y451017D01*
X670008Y450808D01*
X669925Y450558D01*
X669967Y450308D01*
X670133Y450100D01*
X670967Y449683D01*
X671342Y449392D01*
X671592Y448975D01*
X671675Y448600D01*
X669925D01*
G01X667800D02*
Y451100D01*
X668300Y450600D01*
G01Y448600D02*
X667300D01*
G01X664800D02*
Y451100D01*
X665300Y450600D01*
G01Y448600D02*
X664300D01*
G01X705612Y417635D02*
X708112D01*
Y418676D01*
X707987Y419010D01*
X707820Y419218D01*
X707487Y419301D01*
X707154Y419218D01*
X706945Y418968D01*
X706820Y418676D01*
Y417635D01*
G01Y418676D02*
X705612Y419301D01*
G01X707695Y420676D02*
X707945Y420926D01*
X708070Y421218D01*
X708112Y421551D01*
X708029Y421968D01*
X707820Y422260D01*
X707570Y422343D01*
X707320Y422301D01*
X707112Y422135D01*
X706695Y421301D01*
X706404Y420926D01*
X705987Y420676D01*
X705612Y420593D01*
Y422343D01*
G01X705987Y423551D02*
X705779Y423801D01*
X705654Y424093D01*
X705612Y424468D01*
X705695Y424843D01*
X705862Y425135D01*
X706154Y425343D01*
X706487Y425385D01*
X706820Y425301D01*
X707029Y425093D01*
X707195Y424801D01*
X707237Y424510D01*
X707195Y424218D01*
X707029Y423843D01*
X708112Y423968D01*
Y425093D01*
G01X706112Y426551D02*
X705820Y426801D01*
X705654Y427135D01*
X705612Y427510D01*
X705654Y427843D01*
X705862Y428176D01*
X706112Y428385D01*
X706362Y428426D01*
X706654Y428343D01*
X706862Y428051D01*
X706945Y427760D01*
Y427385D01*
G01Y427760D02*
X707070Y428010D01*
X707279Y428218D01*
X707529Y428301D01*
X707779Y428218D01*
X707987Y428010D01*
X708112Y427635D01*
X708070Y427260D01*
X707904Y426885D01*
G01X682550Y417294D02*
X685050D01*
Y418335D01*
X684925Y418669D01*
X684758Y418877D01*
X684425Y418960D01*
X684092Y418877D01*
X683883Y418627D01*
X683758Y418335D01*
Y417294D01*
G01Y418335D02*
X682550Y418960D01*
G01Y421127D02*
X685050D01*
X684550Y420627D01*
G01X682550D02*
Y421627D01*
G01Y424627D02*
X685050D01*
X683258Y423085D01*
Y425169D01*
G01X682550Y427627D02*
X685050D01*
X683258Y426085D01*
Y428169D01*
G01X678369Y417172D02*
X680869D01*
Y418213D01*
X680744Y418547D01*
X680577Y418755D01*
X680244Y418838D01*
X679911Y418755D01*
X679702Y418505D01*
X679577Y418213D01*
Y417172D01*
G01Y418213D02*
X678369Y418838D01*
G01Y421005D02*
X680869D01*
X680369Y420505D01*
G01X678369D02*
Y421505D01*
G01Y424505D02*
X680869D01*
X679077Y422963D01*
Y425047D01*
G01X678869Y426088D02*
X678577Y426338D01*
X678411Y426672D01*
X678369Y427047D01*
X678411Y427380D01*
X678619Y427713D01*
X678869Y427922D01*
X679119Y427963D01*
X679411Y427880D01*
X679619Y427588D01*
X679702Y427297D01*
Y426922D01*
G01Y427297D02*
X679827Y427547D01*
X680036Y427755D01*
X680286Y427838D01*
X680536Y427755D01*
X680744Y427547D01*
X680869Y427172D01*
X680827Y426797D01*
X680661Y426422D01*
G01X691399Y417254D02*
X693899D01*
Y418295D01*
X693774Y418629D01*
X693607Y418837D01*
X693274Y418920D01*
X692941Y418837D01*
X692732Y418587D01*
X692607Y418295D01*
Y417254D01*
G01Y418295D02*
X691399Y418920D01*
G01Y421087D02*
X693899D01*
X693399Y420587D01*
G01X691399D02*
Y421587D01*
G01X691899Y423170D02*
X691607Y423420D01*
X691441Y423754D01*
X691399Y424129D01*
X691441Y424462D01*
X691649Y424795D01*
X691899Y425004D01*
X692149Y425045D01*
X692441Y424962D01*
X692649Y424670D01*
X692732Y424379D01*
Y424004D01*
G01Y424379D02*
X692857Y424629D01*
X693066Y424837D01*
X693316Y424920D01*
X693566Y424837D01*
X693774Y424629D01*
X693899Y424254D01*
X693857Y423879D01*
X693691Y423504D01*
G01X691691Y426379D02*
X691482Y426670D01*
X691399Y427004D01*
X691482Y427337D01*
X691732Y427629D01*
X692107Y427837D01*
X692482Y427920D01*
X692941D01*
X693316Y427837D01*
X693649Y427629D01*
X693816Y427379D01*
X693899Y427087D01*
X693816Y426754D01*
X693649Y426504D01*
X693399Y426337D01*
X693066Y426254D01*
X692774Y426337D01*
X692482Y426545D01*
X692316Y426795D01*
X692274Y427087D01*
X692357Y427420D01*
X692566Y427670D01*
X692941Y427920D01*
G01X687096Y417213D02*
X689596D01*
Y418254D01*
X689471Y418588D01*
X689304Y418796D01*
X688971Y418879D01*
X688638Y418796D01*
X688429Y418546D01*
X688304Y418254D01*
Y417213D01*
G01Y418254D02*
X687096Y418879D01*
G01Y421046D02*
X689596D01*
X689096Y420546D01*
G01X687096D02*
Y421546D01*
G01X687596Y423129D02*
X687304Y423379D01*
X687138Y423713D01*
X687096Y424088D01*
X687138Y424421D01*
X687346Y424754D01*
X687596Y424963D01*
X687846Y425004D01*
X688138Y424921D01*
X688346Y424629D01*
X688429Y424338D01*
Y423963D01*
G01Y424338D02*
X688554Y424588D01*
X688763Y424796D01*
X689013Y424879D01*
X689263Y424796D01*
X689471Y424588D01*
X689596Y424213D01*
X689554Y423838D01*
X689388Y423463D01*
G01X687096Y427046D02*
X687138Y427338D01*
X687263Y427671D01*
X687471Y427879D01*
X687763Y427963D01*
X688054Y427879D01*
X688304Y427629D01*
X688429Y427254D01*
Y426838D01*
X688513Y426588D01*
X688721Y426379D01*
X689013Y426296D01*
X689304Y426421D01*
X689513Y426713D01*
X689596Y427046D01*
X689513Y427379D01*
X689304Y427671D01*
X689013Y427796D01*
X688721Y427713D01*
X688513Y427504D01*
X688429Y427254D01*
Y426838D01*
X688304Y426463D01*
X688054Y426213D01*
X687763Y426129D01*
X687471Y426213D01*
X687263Y426421D01*
X687138Y426754D01*
X687096Y427046D01*
G01X696079Y417273D02*
X698579D01*
Y418314D01*
X698454Y418648D01*
X698287Y418856D01*
X697954Y418939D01*
X697621Y418856D01*
X697412Y418606D01*
X697287Y418314D01*
Y417273D01*
G01Y418314D02*
X696079Y418939D01*
G01Y421106D02*
X698579D01*
X698079Y420606D01*
G01X696079D02*
Y421606D01*
G01X698162Y423314D02*
X698412Y423564D01*
X698537Y423856D01*
X698579Y424189D01*
X698496Y424606D01*
X698287Y424898D01*
X698037Y424981D01*
X697787Y424939D01*
X697579Y424773D01*
X697162Y423939D01*
X696871Y423564D01*
X696454Y423314D01*
X696079Y423231D01*
Y424981D01*
G01Y427023D02*
X696621Y427106D01*
X697079Y427231D01*
X697496Y427398D01*
X697954Y427606D01*
X698579Y427939D01*
Y426273D01*
G01X700284Y417232D02*
X702784D01*
Y418273D01*
X702659Y418607D01*
X702492Y418815D01*
X702159Y418898D01*
X701826Y418815D01*
X701617Y418565D01*
X701492Y418273D01*
Y417232D01*
G01Y418273D02*
X700284Y418898D01*
G01Y421065D02*
X702784D01*
X702284Y420565D01*
G01X700284D02*
Y421565D01*
G01X702367Y423273D02*
X702617Y423523D01*
X702742Y423815D01*
X702784Y424148D01*
X702701Y424565D01*
X702492Y424857D01*
X702242Y424940D01*
X701992Y424898D01*
X701784Y424732D01*
X701367Y423898D01*
X701076Y423523D01*
X700659Y423273D01*
X700284Y423190D01*
Y424940D01*
G01X701326Y426273D02*
X701617Y426565D01*
X701784Y426815D01*
X701867Y427148D01*
X701784Y427440D01*
X701617Y427648D01*
X701367Y427815D01*
X701076Y427857D01*
X700826Y427815D01*
X700576Y427648D01*
X700367Y427398D01*
X700284Y427107D01*
X700367Y426773D01*
X700617Y426482D01*
X700992Y426315D01*
X701409Y426273D01*
X701951Y426357D01*
X702242Y426482D01*
X702534Y426690D01*
X702742Y426982D01*
X702784Y427273D01*
X702701Y427565D01*
X702492Y427773D01*
G01X665483Y485400D02*
Y487900D01*
X664442D01*
X664108Y487775D01*
X663900Y487608D01*
X663817Y487275D01*
X663900Y486942D01*
X664150Y486733D01*
X664442Y486608D01*
X665483D01*
G01X664442D02*
X663817Y485400D01*
G01X662442Y487483D02*
X662192Y487733D01*
X661900Y487858D01*
X661567Y487900D01*
X661150Y487817D01*
X660858Y487608D01*
X660775Y487358D01*
X660817Y487108D01*
X660983Y486900D01*
X661817Y486483D01*
X662192Y486192D01*
X662442Y485775D01*
X662525Y485400D01*
X660775D01*
G01X659442Y486442D02*
X659150Y486733D01*
X658900Y486900D01*
X658567Y486983D01*
X658275Y486900D01*
X658067Y486733D01*
X657900Y486483D01*
X657858Y486192D01*
X657900Y485942D01*
X658067Y485692D01*
X658317Y485483D01*
X658608Y485400D01*
X658942Y485483D01*
X659233Y485733D01*
X659400Y486108D01*
X659442Y486525D01*
X659358Y487067D01*
X659233Y487358D01*
X659025Y487650D01*
X658733Y487858D01*
X658442Y487900D01*
X658150Y487817D01*
X657942Y487608D01*
G01X656567Y485900D02*
X656317Y485608D01*
X655983Y485442D01*
X655608Y485400D01*
X655275Y485442D01*
X654942Y485650D01*
X654733Y485900D01*
X654692Y486150D01*
X654775Y486442D01*
X655067Y486650D01*
X655358Y486733D01*
X655733D01*
G01X655358D02*
X655108Y486858D01*
X654900Y487067D01*
X654817Y487317D01*
X654900Y487567D01*
X655108Y487775D01*
X655483Y487900D01*
X655858Y487858D01*
X656233Y487692D01*
G01X664483Y479092D02*
X664733Y479217D01*
X665025Y479300D01*
X665358D01*
X665733Y479175D01*
X666025Y478967D01*
X666233Y478717D01*
X666400Y478300D01*
X666442Y477925D01*
X666358Y477550D01*
X666233Y477300D01*
X665983Y477050D01*
X665692Y476883D01*
X665400Y476800D01*
X665108D01*
X664817Y476883D01*
X664567Y477008D01*
X664358Y477175D01*
G01X663317Y477300D02*
X663067Y477008D01*
X662733Y476842D01*
X662358Y476800D01*
X662025Y476842D01*
X661692Y477050D01*
X661483Y477300D01*
X661442Y477550D01*
X661525Y477842D01*
X661817Y478050D01*
X662108Y478133D01*
X662483D01*
G01X662108D02*
X661858Y478258D01*
X661650Y478467D01*
X661567Y478717D01*
X661650Y478967D01*
X661858Y479175D01*
X662233Y479300D01*
X662608Y479258D01*
X662983Y479092D01*
G01X659400Y479300D02*
X659733Y479217D01*
X659983Y479008D01*
X660150Y478758D01*
X660275Y478425D01*
X660317Y478050D01*
X660275Y477675D01*
X660150Y477342D01*
X659983Y477092D01*
X659733Y476883D01*
X659400Y476800D01*
X659067Y476883D01*
X658817Y477092D01*
X658650Y477342D01*
X658525Y477675D01*
X658483Y478050D01*
X658525Y478425D01*
X658650Y478758D01*
X658817Y479008D01*
X659067Y479217D01*
X659400Y479300D01*
G01X657192Y477842D02*
X656900Y478133D01*
X656650Y478300D01*
X656317Y478383D01*
X656025Y478300D01*
X655817Y478133D01*
X655650Y477883D01*
X655608Y477592D01*
X655650Y477342D01*
X655817Y477092D01*
X656067Y476883D01*
X656358Y476800D01*
X656692Y476883D01*
X656983Y477133D01*
X657150Y477508D01*
X657192Y477925D01*
X657108Y478467D01*
X656983Y478758D01*
X656775Y479050D01*
X656483Y479258D01*
X656192Y479300D01*
X655900Y479217D01*
X655692Y479008D01*
G01X693017Y508200D02*
Y506408D01*
X692850Y506033D01*
X692517Y505783D01*
X692100Y505700D01*
X691683Y505783D01*
X691350Y506033D01*
X691183Y506408D01*
Y508200D01*
G01X689100Y505700D02*
Y508200D01*
X689600Y507700D01*
G01Y505700D02*
X688600D01*
G01X686100D02*
Y508200D01*
X686600Y507700D01*
G01Y505700D02*
X685600D01*
G01X670892Y497417D02*
X671017Y497167D01*
X671100Y496875D01*
Y496542D01*
X670975Y496167D01*
X670767Y495875D01*
X670517Y495667D01*
X670100Y495500D01*
X669725Y495458D01*
X669350Y495542D01*
X669100Y495667D01*
X668850Y495917D01*
X668683Y496208D01*
X668600Y496500D01*
Y496792D01*
X668683Y497083D01*
X668808Y497333D01*
X668975Y497542D01*
G01X670683Y498708D02*
X670933Y498958D01*
X671058Y499250D01*
X671100Y499583D01*
X671017Y500000D01*
X670808Y500292D01*
X670558Y500375D01*
X670308Y500333D01*
X670100Y500167D01*
X669683Y499333D01*
X669392Y498958D01*
X668975Y498708D01*
X668600Y498625D01*
Y500375D01*
G01X669100Y501583D02*
X668808Y501833D01*
X668642Y502167D01*
X668600Y502542D01*
X668642Y502875D01*
X668850Y503208D01*
X669100Y503417D01*
X669350Y503458D01*
X669642Y503375D01*
X669850Y503083D01*
X669933Y502792D01*
Y502417D01*
G01Y502792D02*
X670058Y503042D01*
X670267Y503250D01*
X670517Y503333D01*
X670767Y503250D01*
X670975Y503042D01*
X671100Y502667D01*
X671058Y502292D01*
X670892Y501917D01*
G01X668600Y506000D02*
X671100D01*
X669308Y504458D01*
Y506542D01*
G01X682333Y548400D02*
Y550900D01*
X681333D01*
X681000Y550775D01*
X680750Y550483D01*
X680667Y550150D01*
X680750Y549817D01*
X680958Y549567D01*
X681333Y549442D01*
X682333D01*
G01X677583Y550692D02*
X677833Y550817D01*
X678125Y550900D01*
X678458D01*
X678833Y550775D01*
X679125Y550567D01*
X679333Y550317D01*
X679500Y549900D01*
X679542Y549525D01*
X679458Y549150D01*
X679333Y548900D01*
X679083Y548650D01*
X678792Y548483D01*
X678500Y548400D01*
X678208D01*
X677917Y548483D01*
X677667Y548608D01*
X677458Y548775D01*
G01X676292Y549442D02*
X676000Y549733D01*
X675750Y549900D01*
X675417Y549983D01*
X675125Y549900D01*
X674917Y549733D01*
X674750Y549483D01*
X674708Y549192D01*
X674750Y548942D01*
X674917Y548692D01*
X675167Y548483D01*
X675458Y548400D01*
X675792Y548483D01*
X676083Y548733D01*
X676250Y549108D01*
X676292Y549525D01*
X676208Y550067D01*
X676083Y550358D01*
X675875Y550650D01*
X675583Y550858D01*
X675292Y550900D01*
X675000Y550817D01*
X674792Y550608D01*
G01X666792Y497117D02*
X666917Y496867D01*
X667000Y496575D01*
Y496242D01*
X666875Y495867D01*
X666667Y495575D01*
X666417Y495367D01*
X666000Y495200D01*
X665625Y495158D01*
X665250Y495242D01*
X665000Y495367D01*
X664750Y495617D01*
X664583Y495908D01*
X664500Y496200D01*
Y496492D01*
X664583Y496783D01*
X664708Y497033D01*
X664875Y497242D01*
G01X666583Y498408D02*
X666833Y498658D01*
X666958Y498950D01*
X667000Y499283D01*
X666917Y499700D01*
X666708Y499992D01*
X666458Y500075D01*
X666208Y500033D01*
X666000Y499867D01*
X665583Y499033D01*
X665292Y498658D01*
X664875Y498408D01*
X664500Y498325D01*
Y500075D01*
G01X665000Y501283D02*
X664708Y501533D01*
X664542Y501867D01*
X664500Y502242D01*
X664542Y502575D01*
X664750Y502908D01*
X665000Y503117D01*
X665250Y503158D01*
X665542Y503075D01*
X665750Y502783D01*
X665833Y502492D01*
Y502117D01*
G01Y502492D02*
X665958Y502742D01*
X666167Y502950D01*
X666417Y503033D01*
X666667Y502950D01*
X666875Y502742D01*
X667000Y502367D01*
X666958Y501992D01*
X666792Y501617D01*
G01X664875Y504283D02*
X664667Y504533D01*
X664542Y504825D01*
X664500Y505200D01*
X664583Y505575D01*
X664750Y505867D01*
X665042Y506075D01*
X665375Y506117D01*
X665708Y506033D01*
X665917Y505825D01*
X666083Y505533D01*
X666125Y505242D01*
X666083Y504950D01*
X665917Y504575D01*
X667000Y504700D01*
Y505825D01*
G01X657033Y525900D02*
Y528400D01*
X655992D01*
X655658Y528275D01*
X655450Y528108D01*
X655367Y527775D01*
X655450Y527442D01*
X655700Y527233D01*
X655992Y527108D01*
X657033D01*
G01X655992D02*
X655367Y525900D01*
G01X652700D02*
Y528400D01*
X654242Y526608D01*
X652158D01*
G01X650908Y526192D02*
X650617Y525983D01*
X650283Y525900D01*
X649950Y525983D01*
X649658Y526233D01*
X649450Y526608D01*
X649367Y526983D01*
Y527442D01*
X649450Y527817D01*
X649658Y528150D01*
X649908Y528317D01*
X650200Y528400D01*
X650533Y528317D01*
X650783Y528150D01*
X650950Y527900D01*
X651033Y527567D01*
X650950Y527275D01*
X650742Y526983D01*
X650492Y526817D01*
X650200Y526775D01*
X649867Y526858D01*
X649617Y527067D01*
X649367Y527442D01*
G01X658933Y517900D02*
Y520400D01*
X657892D01*
X657558Y520275D01*
X657350Y520108D01*
X657267Y519775D01*
X657350Y519442D01*
X657600Y519233D01*
X657892Y519108D01*
X658933D01*
G01X657892D02*
X657267Y517900D01*
G01X654600D02*
Y520400D01*
X656142Y518608D01*
X654058D01*
G01X652100Y517900D02*
X651808Y517942D01*
X651475Y518067D01*
X651267Y518275D01*
X651183Y518567D01*
X651267Y518858D01*
X651517Y519108D01*
X651892Y519233D01*
X652308D01*
X652558Y519317D01*
X652767Y519525D01*
X652850Y519817D01*
X652725Y520108D01*
X652433Y520317D01*
X652100Y520400D01*
X651767Y520317D01*
X651475Y520108D01*
X651350Y519817D01*
X651433Y519525D01*
X651642Y519317D01*
X651892Y519233D01*
X652308D01*
X652683Y519108D01*
X652933Y518858D01*
X653017Y518567D01*
X652933Y518275D01*
X652725Y518067D01*
X652392Y517942D01*
X652100Y517900D01*
G01X708100Y507067D02*
X710600D01*
Y508108D01*
X710475Y508442D01*
X710308Y508650D01*
X709975Y508733D01*
X709642Y508650D01*
X709433Y508400D01*
X709308Y508108D01*
Y507067D01*
G01Y508108D02*
X708100Y508733D01*
G01Y510900D02*
X710600D01*
X710100Y510400D01*
G01X708100D02*
Y511400D01*
G01Y513817D02*
X708642Y513900D01*
X709100Y514025D01*
X709517Y514192D01*
X709975Y514400D01*
X710600Y514733D01*
Y513067D01*
G01X708100Y517400D02*
X710600D01*
X708808Y515858D01*
Y517942D01*
G01X699600Y540167D02*
X702100D01*
Y541208D01*
X701975Y541542D01*
X701808Y541750D01*
X701475Y541833D01*
X701142Y541750D01*
X700933Y541500D01*
X700808Y541208D01*
Y540167D01*
G01Y541208D02*
X699600Y541833D01*
G01Y544000D02*
X702100D01*
X701600Y543500D01*
G01X699600D02*
Y544500D01*
G01Y546917D02*
X700142Y547000D01*
X700600Y547125D01*
X701017Y547292D01*
X701475Y547500D01*
X702100Y547833D01*
Y546167D01*
G01X701683Y549208D02*
X701933Y549458D01*
X702058Y549750D01*
X702100Y550083D01*
X702017Y550500D01*
X701808Y550792D01*
X701558Y550875D01*
X701308Y550833D01*
X701100Y550667D01*
X700683Y549833D01*
X700392Y549458D01*
X699975Y549208D01*
X699600Y549125D01*
Y550875D01*
G01X710300Y492667D02*
X712800D01*
Y493708D01*
X712675Y494042D01*
X712508Y494250D01*
X712175Y494333D01*
X711842Y494250D01*
X711633Y494000D01*
X711508Y493708D01*
Y492667D01*
G01Y493708D02*
X710300Y494333D01*
G01Y496500D02*
X712800D01*
X712300Y496000D01*
G01X710300D02*
Y497000D01*
G01Y500000D02*
X712800D01*
X711008Y498458D01*
Y500542D01*
G01X712383Y501708D02*
X712633Y501958D01*
X712758Y502250D01*
X712800Y502583D01*
X712717Y503000D01*
X712508Y503292D01*
X712258Y503375D01*
X712008Y503333D01*
X711800Y503167D01*
X711383Y502333D01*
X711092Y501958D01*
X710675Y501708D01*
X710300Y501625D01*
Y503375D01*
G01X693133Y501200D02*
Y503700D01*
X692092D01*
X691758Y503575D01*
X691550Y503408D01*
X691467Y503075D01*
X691550Y502742D01*
X691800Y502533D01*
X692092Y502408D01*
X693133D01*
G01X692092D02*
X691467Y501200D01*
G01X689300D02*
Y503700D01*
X689800Y503200D01*
G01Y501200D02*
X688800D01*
G01X686383D02*
X686300Y501742D01*
X686175Y502200D01*
X686008Y502617D01*
X685800Y503075D01*
X685467Y503700D01*
X687133D01*
G01X684217Y501575D02*
X683967Y501367D01*
X683675Y501242D01*
X683300Y501200D01*
X682925Y501283D01*
X682633Y501450D01*
X682425Y501742D01*
X682383Y502075D01*
X682467Y502408D01*
X682675Y502617D01*
X682967Y502783D01*
X683258Y502825D01*
X683550Y502783D01*
X683925Y502617D01*
X683800Y503700D01*
X682675D01*
G01X691500Y548967D02*
X694000D01*
Y550008D01*
X693875Y550342D01*
X693708Y550550D01*
X693375Y550633D01*
X693042Y550550D01*
X692833Y550300D01*
X692708Y550008D01*
Y548967D01*
G01Y550008D02*
X691500Y550633D01*
G01Y552800D02*
X694000D01*
X693500Y552300D01*
G01X691500D02*
Y553300D01*
G01Y555717D02*
X692042Y555800D01*
X692500Y555925D01*
X692917Y556092D01*
X693375Y556300D01*
X694000Y556633D01*
Y554967D01*
G01X692000Y557883D02*
X691708Y558133D01*
X691542Y558467D01*
X691500Y558842D01*
X691542Y559175D01*
X691750Y559508D01*
X692000Y559717D01*
X692250Y559758D01*
X692542Y559675D01*
X692750Y559383D01*
X692833Y559092D01*
Y558717D01*
G01Y559092D02*
X692958Y559342D01*
X693167Y559550D01*
X693417Y559633D01*
X693667Y559550D01*
X693875Y559342D01*
X694000Y558967D01*
X693958Y558592D01*
X693792Y558217D01*
G01X704692Y506217D02*
X704817Y505967D01*
X704900Y505675D01*
Y505342D01*
X704775Y504967D01*
X704567Y504675D01*
X704317Y504467D01*
X703900Y504300D01*
X703525Y504258D01*
X703150Y504342D01*
X702900Y504467D01*
X702650Y504717D01*
X702483Y505008D01*
X702400Y505300D01*
Y505592D01*
X702483Y505883D01*
X702608Y506133D01*
X702775Y506342D01*
G01X702900Y507383D02*
X702608Y507633D01*
X702442Y507967D01*
X702400Y508342D01*
X702442Y508675D01*
X702650Y509008D01*
X702900Y509217D01*
X703150Y509258D01*
X703442Y509175D01*
X703650Y508883D01*
X703733Y508592D01*
Y508217D01*
G01Y508592D02*
X703858Y508842D01*
X704067Y509050D01*
X704317Y509133D01*
X704567Y509050D01*
X704775Y508842D01*
X704900Y508467D01*
X704858Y508092D01*
X704692Y507717D01*
G01X702400Y511300D02*
X704900D01*
X704400Y510800D01*
G01X702400D02*
Y511800D01*
G01X704900Y514300D02*
X704817Y513967D01*
X704608Y513717D01*
X704358Y513550D01*
X704025Y513425D01*
X703650Y513383D01*
X703275Y513425D01*
X702942Y513550D01*
X702692Y513717D01*
X702483Y513967D01*
X702400Y514300D01*
X702483Y514633D01*
X702692Y514883D01*
X702942Y515050D01*
X703275Y515175D01*
X703650Y515217D01*
X704025Y515175D01*
X704358Y515050D01*
X704608Y514883D01*
X704817Y514633D01*
X704900Y514300D01*
G01X670783Y510192D02*
X671033Y510317D01*
X671325Y510400D01*
X671658D01*
X672033Y510275D01*
X672325Y510067D01*
X672533Y509817D01*
X672700Y509400D01*
X672742Y509025D01*
X672658Y508650D01*
X672533Y508400D01*
X672283Y508150D01*
X671992Y507983D01*
X671700Y507900D01*
X671408D01*
X671117Y507983D01*
X670867Y508108D01*
X670658Y508275D01*
G01X669617Y508400D02*
X669367Y508108D01*
X669033Y507942D01*
X668658Y507900D01*
X668325Y507942D01*
X667992Y508150D01*
X667783Y508400D01*
X667742Y508650D01*
X667825Y508942D01*
X668117Y509150D01*
X668408Y509233D01*
X668783D01*
G01X668408D02*
X668158Y509358D01*
X667950Y509567D01*
X667867Y509817D01*
X667950Y510067D01*
X668158Y510275D01*
X668533Y510400D01*
X668908Y510358D01*
X669283Y510192D01*
G01X665700Y510400D02*
X666033Y510317D01*
X666283Y510108D01*
X666450Y509858D01*
X666575Y509525D01*
X666617Y509150D01*
X666575Y508775D01*
X666450Y508442D01*
X666283Y508192D01*
X666033Y507983D01*
X665700Y507900D01*
X665367Y507983D01*
X665117Y508192D01*
X664950Y508442D01*
X664825Y508775D01*
X664783Y509150D01*
X664825Y509525D01*
X664950Y509858D01*
X665117Y510108D01*
X665367Y510317D01*
X665700Y510400D01*
G01X663408Y508192D02*
X663117Y507983D01*
X662783Y507900D01*
X662450Y507983D01*
X662158Y508233D01*
X661950Y508608D01*
X661867Y508983D01*
Y509442D01*
X661950Y509817D01*
X662158Y510150D01*
X662408Y510317D01*
X662700Y510400D01*
X663033Y510317D01*
X663283Y510150D01*
X663450Y509900D01*
X663533Y509567D01*
X663450Y509275D01*
X663242Y508983D01*
X662992Y508817D01*
X662700Y508775D01*
X662367Y508858D01*
X662117Y509067D01*
X661867Y509442D01*
G01X670883Y513692D02*
X671133Y513817D01*
X671425Y513900D01*
X671758D01*
X672133Y513775D01*
X672425Y513567D01*
X672633Y513317D01*
X672800Y512900D01*
X672842Y512525D01*
X672758Y512150D01*
X672633Y511900D01*
X672383Y511650D01*
X672092Y511483D01*
X671800Y511400D01*
X671508D01*
X671217Y511483D01*
X670967Y511608D01*
X670758Y511775D01*
G01X669717Y511900D02*
X669467Y511608D01*
X669133Y511442D01*
X668758Y511400D01*
X668425Y511442D01*
X668092Y511650D01*
X667883Y511900D01*
X667842Y512150D01*
X667925Y512442D01*
X668217Y512650D01*
X668508Y512733D01*
X668883D01*
G01X668508D02*
X668258Y512858D01*
X668050Y513067D01*
X667967Y513317D01*
X668050Y513567D01*
X668258Y513775D01*
X668633Y513900D01*
X669008Y513858D01*
X669383Y513692D01*
G01X665800Y513900D02*
X666133Y513817D01*
X666383Y513608D01*
X666550Y513358D01*
X666675Y513025D01*
X666717Y512650D01*
X666675Y512275D01*
X666550Y511942D01*
X666383Y511692D01*
X666133Y511483D01*
X665800Y511400D01*
X665467Y511483D01*
X665217Y511692D01*
X665050Y511942D01*
X664925Y512275D01*
X664883Y512650D01*
X664925Y513025D01*
X665050Y513358D01*
X665217Y513608D01*
X665467Y513817D01*
X665800Y513900D01*
G01X662800Y511400D02*
X662508Y511442D01*
X662175Y511567D01*
X661967Y511775D01*
X661883Y512067D01*
X661967Y512358D01*
X662217Y512608D01*
X662592Y512733D01*
X663008D01*
X663258Y512817D01*
X663467Y513025D01*
X663550Y513317D01*
X663425Y513608D01*
X663133Y513817D01*
X662800Y513900D01*
X662467Y513817D01*
X662175Y513608D01*
X662050Y513317D01*
X662133Y513025D01*
X662342Y512817D01*
X662592Y512733D01*
X663008D01*
X663383Y512608D01*
X663633Y512358D01*
X663717Y512067D01*
X663633Y511775D01*
X663425Y511567D01*
X663092Y511442D01*
X662800Y511400D01*
G01X698092Y541917D02*
X698217Y541667D01*
X698300Y541375D01*
Y541042D01*
X698175Y540667D01*
X697967Y540375D01*
X697717Y540167D01*
X697300Y540000D01*
X696925Y539958D01*
X696550Y540042D01*
X696300Y540167D01*
X696050Y540417D01*
X695883Y540708D01*
X695800Y541000D01*
Y541292D01*
X695883Y541583D01*
X696008Y541833D01*
X696175Y542042D01*
G01X696300Y543083D02*
X696008Y543333D01*
X695842Y543667D01*
X695800Y544042D01*
X695842Y544375D01*
X696050Y544708D01*
X696300Y544917D01*
X696550Y544958D01*
X696842Y544875D01*
X697050Y544583D01*
X697133Y544292D01*
Y543917D01*
G01Y544292D02*
X697258Y544542D01*
X697467Y544750D01*
X697717Y544833D01*
X697967Y544750D01*
X698175Y544542D01*
X698300Y544167D01*
X698258Y543792D01*
X698092Y543417D01*
G01X698300Y547000D02*
X698217Y546667D01*
X698008Y546417D01*
X697758Y546250D01*
X697425Y546125D01*
X697050Y546083D01*
X696675Y546125D01*
X696342Y546250D01*
X696092Y546417D01*
X695883Y546667D01*
X695800Y547000D01*
X695883Y547333D01*
X696092Y547583D01*
X696342Y547750D01*
X696675Y547875D01*
X697050Y547917D01*
X697425Y547875D01*
X697758Y547750D01*
X698008Y547583D01*
X698217Y547333D01*
X698300Y547000D01*
G01X695800Y549917D02*
X696342Y550000D01*
X696800Y550125D01*
X697217Y550292D01*
X697675Y550500D01*
X698300Y550833D01*
Y549167D01*
G01X664917Y564100D02*
Y562308D01*
X664750Y561933D01*
X664417Y561683D01*
X664000Y561600D01*
X663583Y561683D01*
X663250Y561933D01*
X663083Y562308D01*
Y564100D01*
G01X661708Y561892D02*
X661417Y561683D01*
X661083Y561600D01*
X660750Y561683D01*
X660458Y561933D01*
X660250Y562308D01*
X660167Y562683D01*
Y563142D01*
X660250Y563517D01*
X660458Y563850D01*
X660708Y564017D01*
X661000Y564100D01*
X661333Y564017D01*
X661583Y563850D01*
X661750Y563600D01*
X661833Y563267D01*
X661750Y562975D01*
X661542Y562683D01*
X661292Y562517D01*
X661000Y562475D01*
X660667Y562558D01*
X660417Y562767D01*
X660167Y563142D01*
G01X716483Y572692D02*
X716733Y572817D01*
X717025Y572900D01*
X717358D01*
X717733Y572775D01*
X718025Y572567D01*
X718233Y572317D01*
X718400Y571900D01*
X718442Y571525D01*
X718358Y571150D01*
X718233Y570900D01*
X717983Y570650D01*
X717692Y570483D01*
X717400Y570400D01*
X717108D01*
X716817Y570483D01*
X716567Y570608D01*
X716358Y570775D01*
G01X715192Y572483D02*
X714942Y572733D01*
X714650Y572858D01*
X714317Y572900D01*
X713900Y572817D01*
X713608Y572608D01*
X713525Y572358D01*
X713567Y572108D01*
X713733Y571900D01*
X714567Y571483D01*
X714942Y571192D01*
X715192Y570775D01*
X715275Y570400D01*
X713525D01*
G01X712317Y570775D02*
X712067Y570567D01*
X711775Y570442D01*
X711400Y570400D01*
X711025Y570483D01*
X710733Y570650D01*
X710525Y570942D01*
X710483Y571275D01*
X710567Y571608D01*
X710775Y571817D01*
X711067Y571983D01*
X711358Y572025D01*
X711650Y571983D01*
X712025Y571817D01*
X711900Y572900D01*
X710775D01*
G01X708400D02*
X708733Y572817D01*
X708983Y572608D01*
X709150Y572358D01*
X709275Y572025D01*
X709317Y571650D01*
X709275Y571275D01*
X709150Y570942D01*
X708983Y570692D01*
X708733Y570483D01*
X708400Y570400D01*
X708067Y570483D01*
X707817Y570692D01*
X707650Y570942D01*
X707525Y571275D01*
X707483Y571650D01*
X707525Y572025D01*
X707650Y572358D01*
X707817Y572608D01*
X708067Y572817D01*
X708400Y572900D01*
G01X702465Y559474D02*
X704965D01*
Y560515D01*
X704840Y560849D01*
X704673Y561057D01*
X704340Y561140D01*
X704007Y561057D01*
X703798Y560807D01*
X703673Y560515D01*
Y559474D01*
G01Y560515D02*
X702465Y561140D01*
G01X702840Y562390D02*
X702632Y562640D01*
X702507Y562932D01*
X702465Y563307D01*
X702548Y563682D01*
X702715Y563974D01*
X703007Y564182D01*
X703340Y564224D01*
X703673Y564140D01*
X703882Y563932D01*
X704048Y563640D01*
X704090Y563349D01*
X704048Y563057D01*
X703882Y562682D01*
X704965Y562807D01*
Y563932D01*
G01X702465Y566307D02*
X704965D01*
X704465Y565807D01*
G01X702465D02*
Y566807D01*
G01X702500Y568967D02*
X705000D01*
Y570008D01*
X704875Y570342D01*
X704708Y570550D01*
X704375Y570633D01*
X704042Y570550D01*
X703833Y570300D01*
X703708Y570008D01*
Y568967D01*
G01Y570008D02*
X702500Y570633D01*
G01X702875Y571883D02*
X702667Y572133D01*
X702542Y572425D01*
X702500Y572800D01*
X702583Y573175D01*
X702750Y573467D01*
X703042Y573675D01*
X703375Y573717D01*
X703708Y573633D01*
X703917Y573425D01*
X704083Y573133D01*
X704125Y572842D01*
X704083Y572550D01*
X703917Y572175D01*
X705000Y572300D01*
Y573425D01*
G01Y575800D02*
X704917Y575467D01*
X704708Y575217D01*
X704458Y575050D01*
X704125Y574925D01*
X703750Y574883D01*
X703375Y574925D01*
X703042Y575050D01*
X702792Y575217D01*
X702583Y575467D01*
X702500Y575800D01*
X702583Y576133D01*
X702792Y576383D01*
X703042Y576550D01*
X703375Y576675D01*
X703750Y576717D01*
X704125Y576675D01*
X704458Y576550D01*
X704708Y576383D01*
X704917Y576133D01*
X705000Y575800D01*
G01X677533Y564900D02*
Y567400D01*
X676492D01*
X676158Y567275D01*
X675950Y567108D01*
X675867Y566775D01*
X675950Y566442D01*
X676200Y566233D01*
X676492Y566108D01*
X677533D01*
G01X676492D02*
X675867Y564900D01*
G01X673700D02*
Y567400D01*
X674200Y566900D01*
G01Y564900D02*
X673200D01*
G01X671492Y565942D02*
X671200Y566233D01*
X670950Y566400D01*
X670617Y566483D01*
X670325Y566400D01*
X670117Y566233D01*
X669950Y565983D01*
X669908Y565692D01*
X669950Y565442D01*
X670117Y565192D01*
X670367Y564983D01*
X670658Y564900D01*
X670992Y564983D01*
X671283Y565233D01*
X671450Y565608D01*
X671492Y566025D01*
X671408Y566567D01*
X671283Y566858D01*
X671075Y567150D01*
X670783Y567358D01*
X670492Y567400D01*
X670200Y567317D01*
X669992Y567108D01*
G01X667200Y564900D02*
Y567400D01*
X668742Y565608D01*
X666658D01*
G01X677233Y568700D02*
Y571200D01*
X676192D01*
X675858Y571075D01*
X675650Y570908D01*
X675567Y570575D01*
X675650Y570242D01*
X675900Y570033D01*
X676192Y569908D01*
X677233D01*
G01X676192D02*
X675567Y568700D01*
G01X673400D02*
Y571200D01*
X673900Y570700D01*
G01Y568700D02*
X672900D01*
G01X671192Y569742D02*
X670900Y570033D01*
X670650Y570200D01*
X670317Y570283D01*
X670025Y570200D01*
X669817Y570033D01*
X669650Y569783D01*
X669608Y569492D01*
X669650Y569242D01*
X669817Y568992D01*
X670067Y568783D01*
X670358Y568700D01*
X670692Y568783D01*
X670983Y569033D01*
X671150Y569408D01*
X671192Y569825D01*
X671108Y570367D01*
X670983Y570658D01*
X670775Y570950D01*
X670483Y571158D01*
X670192Y571200D01*
X669900Y571117D01*
X669692Y570908D01*
G01X668192Y570783D02*
X667942Y571033D01*
X667650Y571158D01*
X667317Y571200D01*
X666900Y571117D01*
X666608Y570908D01*
X666525Y570658D01*
X666567Y570408D01*
X666733Y570200D01*
X667567Y569783D01*
X667942Y569492D01*
X668192Y569075D01*
X668275Y568700D01*
X666525D01*
G01X718033Y566700D02*
Y569200D01*
X716992D01*
X716658Y569075D01*
X716450Y568908D01*
X716367Y568575D01*
X716450Y568242D01*
X716700Y568033D01*
X716992Y567908D01*
X718033D01*
G01X716992D02*
X716367Y566700D01*
G01X714992Y568783D02*
X714742Y569033D01*
X714450Y569158D01*
X714117Y569200D01*
X713700Y569117D01*
X713408Y568908D01*
X713325Y568658D01*
X713367Y568408D01*
X713533Y568200D01*
X714367Y567783D01*
X714742Y567492D01*
X714992Y567075D01*
X715075Y566700D01*
X713325D01*
G01X712117Y567075D02*
X711867Y566867D01*
X711575Y566742D01*
X711200Y566700D01*
X710825Y566783D01*
X710533Y566950D01*
X710325Y567242D01*
X710283Y567575D01*
X710367Y567908D01*
X710575Y568117D01*
X710867Y568283D01*
X711158Y568325D01*
X711450Y568283D01*
X711825Y568117D01*
X711700Y569200D01*
X710575D01*
G01X708200Y566700D02*
Y569200D01*
X708700Y568700D01*
G01Y566700D02*
X707700D01*
G01X677533Y561200D02*
Y563700D01*
X676492D01*
X676158Y563575D01*
X675950Y563408D01*
X675867Y563075D01*
X675950Y562742D01*
X676200Y562533D01*
X676492Y562408D01*
X677533D01*
G01X676492D02*
X675867Y561200D01*
G01X673700D02*
Y563700D01*
X674200Y563200D01*
G01Y561200D02*
X673200D01*
G01X671492Y562242D02*
X671200Y562533D01*
X670950Y562700D01*
X670617Y562783D01*
X670325Y562700D01*
X670117Y562533D01*
X669950Y562283D01*
X669908Y561992D01*
X669950Y561742D01*
X670117Y561492D01*
X670367Y561283D01*
X670658Y561200D01*
X670992Y561283D01*
X671283Y561533D01*
X671450Y561908D01*
X671492Y562325D01*
X671408Y562867D01*
X671283Y563158D01*
X671075Y563450D01*
X670783Y563658D01*
X670492Y563700D01*
X670200Y563617D01*
X669992Y563408D01*
G01X668492Y562242D02*
X668200Y562533D01*
X667950Y562700D01*
X667617Y562783D01*
X667325Y562700D01*
X667117Y562533D01*
X666950Y562283D01*
X666908Y561992D01*
X666950Y561742D01*
X667117Y561492D01*
X667367Y561283D01*
X667658Y561200D01*
X667992Y561283D01*
X668283Y561533D01*
X668450Y561908D01*
X668492Y562325D01*
X668408Y562867D01*
X668283Y563158D01*
X668075Y563450D01*
X667783Y563658D01*
X667492Y563700D01*
X667200Y563617D01*
X666992Y563408D01*
G01X659533Y568100D02*
Y570600D01*
X658492D01*
X658158Y570475D01*
X657950Y570308D01*
X657867Y569975D01*
X657950Y569642D01*
X658200Y569433D01*
X658492Y569308D01*
X659533D01*
G01X658492D02*
X657867Y568100D01*
G01X655700D02*
Y570600D01*
X656200Y570100D01*
G01Y568100D02*
X655200D01*
G01X653492Y569142D02*
X653200Y569433D01*
X652950Y569600D01*
X652617Y569683D01*
X652325Y569600D01*
X652117Y569433D01*
X651950Y569183D01*
X651908Y568892D01*
X651950Y568642D01*
X652117Y568392D01*
X652367Y568183D01*
X652658Y568100D01*
X652992Y568183D01*
X653283Y568433D01*
X653450Y568808D01*
X653492Y569225D01*
X653408Y569767D01*
X653283Y570058D01*
X653075Y570350D01*
X652783Y570558D01*
X652492Y570600D01*
X652200Y570517D01*
X651992Y570308D01*
G01X650617Y568600D02*
X650367Y568308D01*
X650033Y568142D01*
X649658Y568100D01*
X649325Y568142D01*
X648992Y568350D01*
X648783Y568600D01*
X648742Y568850D01*
X648825Y569142D01*
X649117Y569350D01*
X649408Y569433D01*
X649783D01*
G01X649408D02*
X649158Y569558D01*
X648950Y569767D01*
X648867Y570017D01*
X648950Y570267D01*
X649158Y570475D01*
X649533Y570600D01*
X649908Y570558D01*
X650283Y570392D01*
G01X690488Y766052D02*
Y768552D01*
X689447D01*
X689113Y768427D01*
X688905Y768260D01*
X688822Y767927D01*
X688905Y767594D01*
X689155Y767385D01*
X689447Y767260D01*
X690488D01*
G01X689447D02*
X688822Y766052D01*
G01X687447Y768135D02*
X687197Y768385D01*
X686905Y768510D01*
X686572Y768552D01*
X686155Y768469D01*
X685863Y768260D01*
X685780Y768010D01*
X685822Y767760D01*
X685988Y767552D01*
X686822Y767135D01*
X687197Y766844D01*
X687447Y766427D01*
X687530Y766052D01*
X685780D01*
G01X684447Y767094D02*
X684155Y767385D01*
X683905Y767552D01*
X683572Y767635D01*
X683280Y767552D01*
X683072Y767385D01*
X682905Y767135D01*
X682863Y766844D01*
X682905Y766594D01*
X683072Y766344D01*
X683322Y766135D01*
X683613Y766052D01*
X683947Y766135D01*
X684238Y766385D01*
X684405Y766760D01*
X684447Y767177D01*
X684363Y767719D01*
X684238Y768010D01*
X684030Y768302D01*
X683738Y768510D01*
X683447Y768552D01*
X683155Y768469D01*
X682947Y768260D01*
G01X681572Y766427D02*
X681322Y766219D01*
X681030Y766094D01*
X680655Y766052D01*
X680280Y766135D01*
X679988Y766302D01*
X679780Y766594D01*
X679738Y766927D01*
X679822Y767260D01*
X680030Y767469D01*
X680322Y767635D01*
X680613Y767677D01*
X680905Y767635D01*
X681280Y767469D01*
X681155Y768552D01*
X680030D01*
G01X717288Y761152D02*
Y763652D01*
X716247D01*
X715913Y763527D01*
X715705Y763360D01*
X715622Y763027D01*
X715705Y762694D01*
X715955Y762485D01*
X716247Y762360D01*
X717288D01*
G01X716247D02*
X715622Y761152D01*
G01X714247Y763235D02*
X713997Y763485D01*
X713705Y763610D01*
X713372Y763652D01*
X712955Y763569D01*
X712663Y763360D01*
X712580Y763110D01*
X712622Y762860D01*
X712788Y762652D01*
X713622Y762235D01*
X713997Y761944D01*
X714247Y761527D01*
X714330Y761152D01*
X712580D01*
G01X711247Y762194D02*
X710955Y762485D01*
X710705Y762652D01*
X710372Y762735D01*
X710080Y762652D01*
X709872Y762485D01*
X709705Y762235D01*
X709663Y761944D01*
X709705Y761694D01*
X709872Y761444D01*
X710122Y761235D01*
X710413Y761152D01*
X710747Y761235D01*
X711038Y761485D01*
X711205Y761860D01*
X711247Y762277D01*
X711163Y762819D01*
X711038Y763110D01*
X710830Y763402D01*
X710538Y763610D01*
X710247Y763652D01*
X709955Y763569D01*
X709747Y763360D01*
G01X706955Y761152D02*
Y763652D01*
X708497Y761860D01*
X706413D01*
G01X690098Y837194D02*
Y839694D01*
X689057D01*
X688723Y839569D01*
X688515Y839402D01*
X688432Y839069D01*
X688515Y838736D01*
X688765Y838527D01*
X689057Y838402D01*
X690098D01*
G01X689057D02*
X688432Y837194D01*
G01X687057Y839277D02*
X686807Y839527D01*
X686515Y839652D01*
X686182Y839694D01*
X685765Y839611D01*
X685473Y839402D01*
X685390Y839152D01*
X685432Y838902D01*
X685598Y838694D01*
X686432Y838277D01*
X686807Y837986D01*
X687057Y837569D01*
X687140Y837194D01*
X685390D01*
G01X683348D02*
X683265Y837736D01*
X683140Y838194D01*
X682973Y838611D01*
X682765Y839069D01*
X682432Y839694D01*
X684098D01*
G01X681057Y838236D02*
X680765Y838527D01*
X680515Y838694D01*
X680182Y838777D01*
X679890Y838694D01*
X679682Y838527D01*
X679515Y838277D01*
X679473Y837986D01*
X679515Y837736D01*
X679682Y837486D01*
X679932Y837277D01*
X680223Y837194D01*
X680557Y837277D01*
X680848Y837527D01*
X681015Y837902D01*
X681057Y838319D01*
X680973Y838861D01*
X680848Y839152D01*
X680640Y839444D01*
X680348Y839652D01*
X680057Y839694D01*
X679765Y839611D01*
X679557Y839402D01*
G01X717010Y832879D02*
Y835379D01*
X715969D01*
X715635Y835254D01*
X715427Y835087D01*
X715344Y834754D01*
X715427Y834421D01*
X715677Y834212D01*
X715969Y834087D01*
X717010D01*
G01X715969D02*
X715344Y832879D01*
G01X713969Y834962D02*
X713719Y835212D01*
X713427Y835337D01*
X713094Y835379D01*
X712677Y835296D01*
X712385Y835087D01*
X712302Y834837D01*
X712344Y834587D01*
X712510Y834379D01*
X713344Y833962D01*
X713719Y833671D01*
X713969Y833254D01*
X714052Y832879D01*
X712302D01*
G01X710260D02*
X710177Y833421D01*
X710052Y833879D01*
X709885Y834296D01*
X709677Y834754D01*
X709344Y835379D01*
X711010D01*
G01X708094Y833254D02*
X707844Y833046D01*
X707552Y832921D01*
X707177Y832879D01*
X706802Y832962D01*
X706510Y833129D01*
X706302Y833421D01*
X706260Y833754D01*
X706344Y834087D01*
X706552Y834296D01*
X706844Y834462D01*
X707135Y834504D01*
X707427Y834462D01*
X707802Y834296D01*
X707677Y835379D01*
X706552D01*
G01X690228Y828840D02*
Y831340D01*
X689187D01*
X688853Y831215D01*
X688645Y831048D01*
X688562Y830715D01*
X688645Y830382D01*
X688895Y830173D01*
X689187Y830048D01*
X690228D01*
G01X689187D02*
X688562Y828840D01*
G01X687187Y830923D02*
X686937Y831173D01*
X686645Y831298D01*
X686312Y831340D01*
X685895Y831257D01*
X685603Y831048D01*
X685520Y830798D01*
X685562Y830548D01*
X685728Y830340D01*
X686562Y829923D01*
X686937Y829632D01*
X687187Y829215D01*
X687270Y828840D01*
X685520D01*
G01X683478D02*
X683395Y829382D01*
X683270Y829840D01*
X683103Y830257D01*
X682895Y830715D01*
X682562Y831340D01*
X684228D01*
G01X679895Y828840D02*
Y831340D01*
X681437Y829548D01*
X679353D01*
G01X717788Y797752D02*
Y800252D01*
X716747D01*
X716413Y800127D01*
X716205Y799960D01*
X716122Y799627D01*
X716205Y799294D01*
X716455Y799085D01*
X716747Y798960D01*
X717788D01*
G01X716747D02*
X716122Y797752D01*
G01X714747Y799835D02*
X714497Y800085D01*
X714205Y800210D01*
X713872Y800252D01*
X713455Y800169D01*
X713163Y799960D01*
X713080Y799710D01*
X713122Y799460D01*
X713288Y799252D01*
X714122Y798835D01*
X714497Y798544D01*
X714747Y798127D01*
X714830Y797752D01*
X713080D01*
G01X711038D02*
X710955Y798294D01*
X710830Y798752D01*
X710663Y799169D01*
X710455Y799627D01*
X710122Y800252D01*
X711788D01*
G01X708872Y798252D02*
X708622Y797960D01*
X708288Y797794D01*
X707913Y797752D01*
X707580Y797794D01*
X707247Y798002D01*
X707038Y798252D01*
X706997Y798502D01*
X707080Y798794D01*
X707372Y799002D01*
X707663Y799085D01*
X708038D01*
G01X707663D02*
X707413Y799210D01*
X707205Y799419D01*
X707122Y799669D01*
X707205Y799919D01*
X707413Y800127D01*
X707788Y800252D01*
X708163Y800210D01*
X708538Y800044D01*
G01X713488Y794052D02*
Y796552D01*
X712447D01*
X712113Y796427D01*
X711905Y796260D01*
X711822Y795927D01*
X711905Y795594D01*
X712155Y795385D01*
X712447Y795260D01*
X713488D01*
G01X712447D02*
X711822Y794052D01*
G01X710447Y796135D02*
X710197Y796385D01*
X709905Y796510D01*
X709572Y796552D01*
X709155Y796469D01*
X708863Y796260D01*
X708780Y796010D01*
X708822Y795760D01*
X708988Y795552D01*
X709822Y795135D01*
X710197Y794844D01*
X710447Y794427D01*
X710530Y794052D01*
X708780D01*
G01X706738D02*
X706655Y794594D01*
X706530Y795052D01*
X706363Y795469D01*
X706155Y795927D01*
X705822Y796552D01*
X707488D01*
G01X704447Y796135D02*
X704197Y796385D01*
X703905Y796510D01*
X703572Y796552D01*
X703155Y796469D01*
X702863Y796260D01*
X702780Y796010D01*
X702822Y795760D01*
X702988Y795552D01*
X703822Y795135D01*
X704197Y794844D01*
X704447Y794427D01*
X704530Y794052D01*
X702780D01*
G01X712288Y789952D02*
Y792452D01*
X711247D01*
X710913Y792327D01*
X710705Y792160D01*
X710622Y791827D01*
X710705Y791494D01*
X710955Y791285D01*
X711247Y791160D01*
X712288D01*
G01X711247D02*
X710622Y789952D01*
G01X709247Y792035D02*
X708997Y792285D01*
X708705Y792410D01*
X708372Y792452D01*
X707955Y792369D01*
X707663Y792160D01*
X707580Y791910D01*
X707622Y791660D01*
X707788Y791452D01*
X708622Y791035D01*
X708997Y790744D01*
X709247Y790327D01*
X709330Y789952D01*
X707580D01*
G01X705538D02*
X705455Y790494D01*
X705330Y790952D01*
X705163Y791369D01*
X704955Y791827D01*
X704622Y792452D01*
X706288D01*
G01X702455Y789952D02*
Y792452D01*
X702955Y791952D01*
G01Y789952D02*
X701955D01*
G01X717088Y786352D02*
Y788852D01*
X716047D01*
X715713Y788727D01*
X715505Y788560D01*
X715422Y788227D01*
X715505Y787894D01*
X715755Y787685D01*
X716047Y787560D01*
X717088D01*
G01X716047D02*
X715422Y786352D01*
G01X714047Y788435D02*
X713797Y788685D01*
X713505Y788810D01*
X713172Y788852D01*
X712755Y788769D01*
X712463Y788560D01*
X712380Y788310D01*
X712422Y788060D01*
X712588Y787852D01*
X713422Y787435D01*
X713797Y787144D01*
X714047Y786727D01*
X714130Y786352D01*
X712380D01*
G01X710338D02*
X710255Y786894D01*
X710130Y787352D01*
X709963Y787769D01*
X709755Y788227D01*
X709422Y788852D01*
X711088D01*
G01X707255D02*
X707588Y788769D01*
X707838Y788560D01*
X708005Y788310D01*
X708130Y787977D01*
X708172Y787602D01*
X708130Y787227D01*
X708005Y786894D01*
X707838Y786644D01*
X707588Y786435D01*
X707255Y786352D01*
X706922Y786435D01*
X706672Y786644D01*
X706505Y786894D01*
X706380Y787227D01*
X706338Y787602D01*
X706380Y787977D01*
X706505Y788310D01*
X706672Y788560D01*
X706922Y788769D01*
X707255Y788852D01*
G01X711088Y782352D02*
Y784852D01*
X710047D01*
X709713Y784727D01*
X709505Y784560D01*
X709422Y784227D01*
X709505Y783894D01*
X709755Y783685D01*
X710047Y783560D01*
X711088D01*
G01X710047D02*
X709422Y782352D01*
G01X708047Y784435D02*
X707797Y784685D01*
X707505Y784810D01*
X707172Y784852D01*
X706755Y784769D01*
X706463Y784560D01*
X706380Y784310D01*
X706422Y784060D01*
X706588Y783852D01*
X707422Y783435D01*
X707797Y783144D01*
X708047Y782727D01*
X708130Y782352D01*
X706380D01*
G01X705047Y783394D02*
X704755Y783685D01*
X704505Y783852D01*
X704172Y783935D01*
X703880Y783852D01*
X703672Y783685D01*
X703505Y783435D01*
X703463Y783144D01*
X703505Y782894D01*
X703672Y782644D01*
X703922Y782435D01*
X704213Y782352D01*
X704547Y782435D01*
X704838Y782685D01*
X705005Y783060D01*
X705047Y783477D01*
X704963Y784019D01*
X704838Y784310D01*
X704630Y784602D01*
X704338Y784810D01*
X704047Y784852D01*
X703755Y784769D01*
X703547Y784560D01*
G01X701963Y782644D02*
X701672Y782435D01*
X701338Y782352D01*
X701005Y782435D01*
X700713Y782685D01*
X700505Y783060D01*
X700422Y783435D01*
Y783894D01*
X700505Y784269D01*
X700713Y784602D01*
X700963Y784769D01*
X701255Y784852D01*
X701588Y784769D01*
X701838Y784602D01*
X702005Y784352D01*
X702088Y784019D01*
X702005Y783727D01*
X701797Y783435D01*
X701547Y783269D01*
X701255Y783227D01*
X700922Y783310D01*
X700672Y783519D01*
X700422Y783894D01*
G01X716288Y778252D02*
Y780752D01*
X715247D01*
X714913Y780627D01*
X714705Y780460D01*
X714622Y780127D01*
X714705Y779794D01*
X714955Y779585D01*
X715247Y779460D01*
X716288D01*
G01X715247D02*
X714622Y778252D01*
G01X713247Y780335D02*
X712997Y780585D01*
X712705Y780710D01*
X712372Y780752D01*
X711955Y780669D01*
X711663Y780460D01*
X711580Y780210D01*
X711622Y779960D01*
X711788Y779752D01*
X712622Y779335D01*
X712997Y779044D01*
X713247Y778627D01*
X713330Y778252D01*
X711580D01*
G01X710247Y779294D02*
X709955Y779585D01*
X709705Y779752D01*
X709372Y779835D01*
X709080Y779752D01*
X708872Y779585D01*
X708705Y779335D01*
X708663Y779044D01*
X708705Y778794D01*
X708872Y778544D01*
X709122Y778335D01*
X709413Y778252D01*
X709747Y778335D01*
X710038Y778585D01*
X710205Y778960D01*
X710247Y779377D01*
X710163Y779919D01*
X710038Y780210D01*
X709830Y780502D01*
X709538Y780710D01*
X709247Y780752D01*
X708955Y780669D01*
X708747Y780460D01*
G01X706455Y778252D02*
X706163Y778294D01*
X705830Y778419D01*
X705622Y778627D01*
X705538Y778919D01*
X705622Y779210D01*
X705872Y779460D01*
X706247Y779585D01*
X706663D01*
X706913Y779669D01*
X707122Y779877D01*
X707205Y780169D01*
X707080Y780460D01*
X706788Y780669D01*
X706455Y780752D01*
X706122Y780669D01*
X705830Y780460D01*
X705705Y780169D01*
X705788Y779877D01*
X705997Y779669D01*
X706247Y779585D01*
X706663D01*
X707038Y779460D01*
X707288Y779210D01*
X707372Y778919D01*
X707288Y778627D01*
X707080Y778419D01*
X706747Y778294D01*
X706455Y778252D01*
G01X690788Y774252D02*
Y776752D01*
X689747D01*
X689413Y776627D01*
X689205Y776460D01*
X689122Y776127D01*
X689205Y775794D01*
X689455Y775585D01*
X689747Y775460D01*
X690788D01*
G01X689747D02*
X689122Y774252D01*
G01X687747Y776335D02*
X687497Y776585D01*
X687205Y776710D01*
X686872Y776752D01*
X686455Y776669D01*
X686163Y776460D01*
X686080Y776210D01*
X686122Y775960D01*
X686288Y775752D01*
X687122Y775335D01*
X687497Y775044D01*
X687747Y774627D01*
X687830Y774252D01*
X686080D01*
G01X684747Y775294D02*
X684455Y775585D01*
X684205Y775752D01*
X683872Y775835D01*
X683580Y775752D01*
X683372Y775585D01*
X683205Y775335D01*
X683163Y775044D01*
X683205Y774794D01*
X683372Y774544D01*
X683622Y774335D01*
X683913Y774252D01*
X684247Y774335D01*
X684538Y774585D01*
X684705Y774960D01*
X684747Y775377D01*
X684663Y775919D01*
X684538Y776210D01*
X684330Y776502D01*
X684038Y776710D01*
X683747Y776752D01*
X683455Y776669D01*
X683247Y776460D01*
G01X681038Y774252D02*
X680955Y774794D01*
X680830Y775252D01*
X680663Y775669D01*
X680455Y776127D01*
X680122Y776752D01*
X681788D01*
G01X716588Y769552D02*
Y772052D01*
X715547D01*
X715213Y771927D01*
X715005Y771760D01*
X714922Y771427D01*
X715005Y771094D01*
X715255Y770885D01*
X715547Y770760D01*
X716588D01*
G01X715547D02*
X714922Y769552D01*
G01X713547Y771635D02*
X713297Y771885D01*
X713005Y772010D01*
X712672Y772052D01*
X712255Y771969D01*
X711963Y771760D01*
X711880Y771510D01*
X711922Y771260D01*
X712088Y771052D01*
X712922Y770635D01*
X713297Y770344D01*
X713547Y769927D01*
X713630Y769552D01*
X711880D01*
G01X710547Y770594D02*
X710255Y770885D01*
X710005Y771052D01*
X709672Y771135D01*
X709380Y771052D01*
X709172Y770885D01*
X709005Y770635D01*
X708963Y770344D01*
X709005Y770094D01*
X709172Y769844D01*
X709422Y769635D01*
X709713Y769552D01*
X710047Y769635D01*
X710338Y769885D01*
X710505Y770260D01*
X710547Y770677D01*
X710463Y771219D01*
X710338Y771510D01*
X710130Y771802D01*
X709838Y772010D01*
X709547Y772052D01*
X709255Y771969D01*
X709047Y771760D01*
G01X707547Y770594D02*
X707255Y770885D01*
X707005Y771052D01*
X706672Y771135D01*
X706380Y771052D01*
X706172Y770885D01*
X706005Y770635D01*
X705963Y770344D01*
X706005Y770094D01*
X706172Y769844D01*
X706422Y769635D01*
X706713Y769552D01*
X707047Y769635D01*
X707338Y769885D01*
X707505Y770260D01*
X707547Y770677D01*
X707463Y771219D01*
X707338Y771510D01*
X707130Y771802D01*
X706838Y772010D01*
X706547Y772052D01*
X706255Y771969D01*
X706047Y771760D01*
G01X688773Y824718D02*
Y827218D01*
X687732D01*
X687398Y827093D01*
X687190Y826926D01*
X687107Y826593D01*
X687190Y826260D01*
X687440Y826051D01*
X687732Y825926D01*
X688773D01*
G01X687732D02*
X687107Y824718D01*
G01X685732Y826801D02*
X685482Y827051D01*
X685190Y827176D01*
X684857Y827218D01*
X684440Y827135D01*
X684148Y826926D01*
X684065Y826676D01*
X684107Y826426D01*
X684273Y826218D01*
X685107Y825801D01*
X685482Y825510D01*
X685732Y825093D01*
X685815Y824718D01*
X684065D01*
G01X682648Y825010D02*
X682357Y824801D01*
X682023Y824718D01*
X681690Y824801D01*
X681398Y825051D01*
X681190Y825426D01*
X681107Y825801D01*
Y826260D01*
X681190Y826635D01*
X681398Y826968D01*
X681648Y827135D01*
X681940Y827218D01*
X682273Y827135D01*
X682523Y826968D01*
X682690Y826718D01*
X682773Y826385D01*
X682690Y826093D01*
X682482Y825801D01*
X682232Y825635D01*
X681940Y825593D01*
X681607Y825676D01*
X681357Y825885D01*
X681107Y826260D01*
G01X679732Y826801D02*
X679482Y827051D01*
X679190Y827176D01*
X678857Y827218D01*
X678440Y827135D01*
X678148Y826926D01*
X678065Y826676D01*
X678107Y826426D01*
X678273Y826218D01*
X679107Y825801D01*
X679482Y825510D01*
X679732Y825093D01*
X679815Y824718D01*
X678065D01*
G01X712398Y853661D02*
Y856161D01*
X711357D01*
X711023Y856036D01*
X710815Y855869D01*
X710732Y855536D01*
X710815Y855203D01*
X711065Y854994D01*
X711357Y854869D01*
X712398D01*
G01X711357D02*
X710732Y853661D01*
G01X709357Y855744D02*
X709107Y855994D01*
X708815Y856119D01*
X708482Y856161D01*
X708065Y856078D01*
X707773Y855869D01*
X707690Y855619D01*
X707732Y855369D01*
X707898Y855161D01*
X708732Y854744D01*
X709107Y854453D01*
X709357Y854036D01*
X709440Y853661D01*
X707690D01*
G01X705565D02*
X705273Y853703D01*
X704940Y853828D01*
X704732Y854036D01*
X704648Y854328D01*
X704732Y854619D01*
X704982Y854869D01*
X705357Y854994D01*
X705773D01*
X706023Y855078D01*
X706232Y855286D01*
X706315Y855578D01*
X706190Y855869D01*
X705898Y856078D01*
X705565Y856161D01*
X705232Y856078D01*
X704940Y855869D01*
X704815Y855578D01*
X704898Y855286D01*
X705107Y855078D01*
X705357Y854994D01*
X705773D01*
X706148Y854869D01*
X706398Y854619D01*
X706482Y854328D01*
X706398Y854036D01*
X706190Y853828D01*
X705857Y853703D01*
X705565Y853661D01*
G01X702565Y856161D02*
X702898Y856078D01*
X703148Y855869D01*
X703315Y855619D01*
X703440Y855286D01*
X703482Y854911D01*
X703440Y854536D01*
X703315Y854203D01*
X703148Y853953D01*
X702898Y853744D01*
X702565Y853661D01*
X702232Y853744D01*
X701982Y853953D01*
X701815Y854203D01*
X701690Y854536D01*
X701648Y854911D01*
X701690Y855286D01*
X701815Y855619D01*
X701982Y855869D01*
X702232Y856078D01*
X702565Y856161D01*
G01X715910Y848352D02*
Y850852D01*
X714869D01*
X714535Y850727D01*
X714327Y850560D01*
X714244Y850227D01*
X714327Y849894D01*
X714577Y849685D01*
X714869Y849560D01*
X715910D01*
G01X714869D02*
X714244Y848352D01*
G01X712869Y850435D02*
X712619Y850685D01*
X712327Y850810D01*
X711994Y850852D01*
X711577Y850769D01*
X711285Y850560D01*
X711202Y850310D01*
X711244Y850060D01*
X711410Y849852D01*
X712244Y849435D01*
X712619Y849144D01*
X712869Y848727D01*
X712952Y848352D01*
X711202D01*
G01X709160D02*
X709077Y848894D01*
X708952Y849352D01*
X708785Y849769D01*
X708577Y850227D01*
X708244Y850852D01*
X709910D01*
G01X706785Y848644D02*
X706494Y848435D01*
X706160Y848352D01*
X705827Y848435D01*
X705535Y848685D01*
X705327Y849060D01*
X705244Y849435D01*
Y849894D01*
X705327Y850269D01*
X705535Y850602D01*
X705785Y850769D01*
X706077Y850852D01*
X706410Y850769D01*
X706660Y850602D01*
X706827Y850352D01*
X706910Y850019D01*
X706827Y849727D01*
X706619Y849435D01*
X706369Y849269D01*
X706077Y849227D01*
X705744Y849310D01*
X705494Y849519D01*
X705244Y849894D01*
G01X689854Y845718D02*
Y848218D01*
X688813D01*
X688479Y848093D01*
X688271Y847926D01*
X688188Y847593D01*
X688271Y847260D01*
X688521Y847051D01*
X688813Y846926D01*
X689854D01*
G01X688813D02*
X688188Y845718D01*
G01X686813Y847801D02*
X686563Y848051D01*
X686271Y848176D01*
X685938Y848218D01*
X685521Y848135D01*
X685229Y847926D01*
X685146Y847676D01*
X685188Y847426D01*
X685354Y847218D01*
X686188Y846801D01*
X686563Y846510D01*
X686813Y846093D01*
X686896Y845718D01*
X685146D01*
G01X683104D02*
X683021Y846260D01*
X682896Y846718D01*
X682729Y847135D01*
X682521Y847593D01*
X682188Y848218D01*
X683854D01*
G01X680021Y845718D02*
X679729Y845760D01*
X679396Y845885D01*
X679188Y846093D01*
X679104Y846385D01*
X679188Y846676D01*
X679438Y846926D01*
X679813Y847051D01*
X680229D01*
X680479Y847135D01*
X680688Y847343D01*
X680771Y847635D01*
X680646Y847926D01*
X680354Y848135D01*
X680021Y848218D01*
X679688Y848135D01*
X679396Y847926D01*
X679271Y847635D01*
X679354Y847343D01*
X679563Y847135D01*
X679813Y847051D01*
X680229D01*
X680604Y846926D01*
X680854Y846676D01*
X680938Y846385D01*
X680854Y846093D01*
X680646Y845885D01*
X680313Y845760D01*
X680021Y845718D01*
G01X716110Y840596D02*
Y843096D01*
X715069D01*
X714735Y842971D01*
X714527Y842804D01*
X714444Y842471D01*
X714527Y842138D01*
X714777Y841929D01*
X715069Y841804D01*
X716110D01*
G01X715069D02*
X714444Y840596D01*
G01X713069Y842679D02*
X712819Y842929D01*
X712527Y843054D01*
X712194Y843096D01*
X711777Y843013D01*
X711485Y842804D01*
X711402Y842554D01*
X711444Y842304D01*
X711610Y842096D01*
X712444Y841679D01*
X712819Y841388D01*
X713069Y840971D01*
X713152Y840596D01*
X711402D01*
G01X709360D02*
X709277Y841138D01*
X709152Y841596D01*
X708985Y842013D01*
X708777Y842471D01*
X708444Y843096D01*
X710110D01*
G01X706360Y840596D02*
X706277Y841138D01*
X706152Y841596D01*
X705985Y842013D01*
X705777Y842471D01*
X705444Y843096D01*
X707110D01*
G01X690843Y857490D02*
Y859990D01*
X689802D01*
X689468Y859865D01*
X689260Y859698D01*
X689177Y859365D01*
X689260Y859032D01*
X689510Y858823D01*
X689802Y858698D01*
X690843D01*
G01X689802D02*
X689177Y857490D01*
G01X687010D02*
Y859990D01*
X687510Y859490D01*
G01Y857490D02*
X686510D01*
G01X684927Y857990D02*
X684677Y857698D01*
X684343Y857532D01*
X683968Y857490D01*
X683635Y857532D01*
X683302Y857740D01*
X683093Y857990D01*
X683052Y858240D01*
X683135Y858532D01*
X683427Y858740D01*
X683718Y858823D01*
X684093D01*
G01X683718D02*
X683468Y858948D01*
X683260Y859157D01*
X683177Y859407D01*
X683260Y859657D01*
X683468Y859865D01*
X683843Y859990D01*
X684218Y859948D01*
X684593Y859782D01*
G01X681093Y857490D02*
X681010Y858032D01*
X680885Y858490D01*
X680718Y858907D01*
X680510Y859365D01*
X680177Y859990D01*
X681843D01*
G01X723383Y464892D02*
X723633Y465017D01*
X723925Y465100D01*
X724258D01*
X724633Y464975D01*
X724925Y464767D01*
X725133Y464517D01*
X725300Y464100D01*
X725342Y463725D01*
X725258Y463350D01*
X725133Y463100D01*
X724883Y462850D01*
X724592Y462683D01*
X724300Y462600D01*
X724008D01*
X723717Y462683D01*
X723467Y462808D01*
X723258Y462975D01*
G01X722092Y464683D02*
X721842Y464933D01*
X721550Y465058D01*
X721217Y465100D01*
X720800Y465017D01*
X720508Y464808D01*
X720425Y464558D01*
X720467Y464308D01*
X720633Y464100D01*
X721467Y463683D01*
X721842Y463392D01*
X722092Y462975D01*
X722175Y462600D01*
X720425D01*
G01X718300D02*
Y465100D01*
X718800Y464600D01*
G01Y462600D02*
X717800D01*
G01X716217Y463100D02*
X715967Y462808D01*
X715633Y462642D01*
X715258Y462600D01*
X714925Y462642D01*
X714592Y462850D01*
X714383Y463100D01*
X714342Y463350D01*
X714425Y463642D01*
X714717Y463850D01*
X715008Y463933D01*
X715383D01*
G01X715008D02*
X714758Y464058D01*
X714550Y464267D01*
X714467Y464517D01*
X714550Y464767D01*
X714758Y464975D01*
X715133Y465100D01*
X715508Y465058D01*
X715883Y464892D01*
G01X724483Y454992D02*
X724733Y455117D01*
X725025Y455200D01*
X725358D01*
X725733Y455075D01*
X726025Y454867D01*
X726233Y454617D01*
X726400Y454200D01*
X726442Y453825D01*
X726358Y453450D01*
X726233Y453200D01*
X725983Y452950D01*
X725692Y452783D01*
X725400Y452700D01*
X725108D01*
X724817Y452783D01*
X724567Y452908D01*
X724358Y453075D01*
G01X723192Y454783D02*
X722942Y455033D01*
X722650Y455158D01*
X722317Y455200D01*
X721900Y455117D01*
X721608Y454908D01*
X721525Y454658D01*
X721567Y454408D01*
X721733Y454200D01*
X722567Y453783D01*
X722942Y453492D01*
X723192Y453075D01*
X723275Y452700D01*
X721525D01*
G01X719400D02*
Y455200D01*
X719900Y454700D01*
G01Y452700D02*
X718900D01*
G01X716400Y455200D02*
X716733Y455117D01*
X716983Y454908D01*
X717150Y454658D01*
X717275Y454325D01*
X717317Y453950D01*
X717275Y453575D01*
X717150Y453242D01*
X716983Y452992D01*
X716733Y452783D01*
X716400Y452700D01*
X716067Y452783D01*
X715817Y452992D01*
X715650Y453242D01*
X715525Y453575D01*
X715483Y453950D01*
X715525Y454325D01*
X715650Y454658D01*
X715817Y454908D01*
X716067Y455117D01*
X716400Y455200D01*
G01X732964Y483317D02*
Y485817D01*
X731923D01*
X731589Y485692D01*
X731381Y485525D01*
X731298Y485192D01*
X731381Y484859D01*
X731631Y484650D01*
X731923Y484525D01*
X732964D01*
G01X731923D02*
X731298Y483317D01*
G01X729131D02*
Y485817D01*
X729631Y485317D01*
G01Y483317D02*
X728631D01*
G01X725631D02*
Y485817D01*
X727173Y484025D01*
X725089D01*
G01X723923Y484359D02*
X723631Y484650D01*
X723381Y484817D01*
X723048Y484900D01*
X722756Y484817D01*
X722548Y484650D01*
X722381Y484400D01*
X722339Y484109D01*
X722381Y483859D01*
X722548Y483609D01*
X722798Y483400D01*
X723089Y483317D01*
X723423Y483400D01*
X723714Y483650D01*
X723881Y484025D01*
X723923Y484442D01*
X723839Y484984D01*
X723714Y485275D01*
X723506Y485567D01*
X723214Y485775D01*
X722923Y485817D01*
X722631Y485734D01*
X722423Y485525D01*
G01X733145Y479520D02*
Y482020D01*
X732104D01*
X731770Y481895D01*
X731562Y481728D01*
X731479Y481395D01*
X731562Y481062D01*
X731812Y480853D01*
X732104Y480728D01*
X733145D01*
G01X732104D02*
X731479Y479520D01*
G01X729312D02*
Y482020D01*
X729812Y481520D01*
G01Y479520D02*
X728812D01*
G01X725812D02*
Y482020D01*
X727354Y480228D01*
X725270D01*
G01X724229Y479895D02*
X723979Y479687D01*
X723687Y479562D01*
X723312Y479520D01*
X722937Y479603D01*
X722645Y479770D01*
X722437Y480062D01*
X722395Y480395D01*
X722479Y480728D01*
X722687Y480937D01*
X722979Y481103D01*
X723270Y481145D01*
X723562Y481103D01*
X723937Y480937D01*
X723812Y482020D01*
X722687D01*
G01X723300Y442700D02*
Y440200D01*
G01X724258Y442700D02*
X722342D01*
G01X721133Y440200D02*
Y442700D01*
X720133D01*
X719800Y442575D01*
X719550Y442283D01*
X719467Y441950D01*
X719550Y441617D01*
X719758Y441367D01*
X720133Y441242D01*
X721133D01*
G01X716800Y440200D02*
Y442700D01*
X718342Y440908D01*
X716258D01*
G01X715008Y440492D02*
X714717Y440283D01*
X714383Y440200D01*
X714050Y440283D01*
X713758Y440533D01*
X713550Y440908D01*
X713467Y441283D01*
Y441742D01*
X713550Y442117D01*
X713758Y442450D01*
X714008Y442617D01*
X714300Y442700D01*
X714633Y442617D01*
X714883Y442450D01*
X715050Y442200D01*
X715133Y441867D01*
X715050Y441575D01*
X714842Y441283D01*
X714592Y441117D01*
X714300Y441075D01*
X713967Y441158D01*
X713717Y441367D01*
X713467Y441742D01*
G01X736833Y524300D02*
Y526800D01*
X735792D01*
X735458Y526675D01*
X735250Y526508D01*
X735167Y526175D01*
X735250Y525842D01*
X735500Y525633D01*
X735792Y525508D01*
X736833D01*
G01X735792D02*
X735167Y524300D01*
G01X733917Y524800D02*
X733667Y524508D01*
X733333Y524342D01*
X732958Y524300D01*
X732625Y524342D01*
X732292Y524550D01*
X732083Y524800D01*
X732042Y525050D01*
X732125Y525342D01*
X732417Y525550D01*
X732708Y525633D01*
X733083D01*
G01X732708D02*
X732458Y525758D01*
X732250Y525967D01*
X732167Y526217D01*
X732250Y526467D01*
X732458Y526675D01*
X732833Y526800D01*
X733208Y526758D01*
X733583Y526592D01*
G01X730917Y524675D02*
X730667Y524467D01*
X730375Y524342D01*
X730000Y524300D01*
X729625Y524383D01*
X729333Y524550D01*
X729125Y524842D01*
X729083Y525175D01*
X729167Y525508D01*
X729375Y525717D01*
X729667Y525883D01*
X729958Y525925D01*
X730250Y525883D01*
X730625Y525717D01*
X730500Y526800D01*
X729375D01*
G01X727708Y524592D02*
X727417Y524383D01*
X727083Y524300D01*
X726750Y524383D01*
X726458Y524633D01*
X726250Y525008D01*
X726167Y525383D01*
Y525842D01*
X726250Y526217D01*
X726458Y526550D01*
X726708Y526717D01*
X727000Y526800D01*
X727333Y526717D01*
X727583Y526550D01*
X727750Y526300D01*
X727833Y525967D01*
X727750Y525675D01*
X727542Y525383D01*
X727292Y525217D01*
X727000Y525175D01*
X726667Y525258D01*
X726417Y525467D01*
X726167Y525842D01*
G01X737333Y520600D02*
Y523100D01*
X736292D01*
X735958Y522975D01*
X735750Y522808D01*
X735667Y522475D01*
X735750Y522142D01*
X736000Y521933D01*
X736292Y521808D01*
X737333D01*
G01X736292D02*
X735667Y520600D01*
G01X734417Y521100D02*
X734167Y520808D01*
X733833Y520642D01*
X733458Y520600D01*
X733125Y520642D01*
X732792Y520850D01*
X732583Y521100D01*
X732542Y521350D01*
X732625Y521642D01*
X732917Y521850D01*
X733208Y521933D01*
X733583D01*
G01X733208D02*
X732958Y522058D01*
X732750Y522267D01*
X732667Y522517D01*
X732750Y522767D01*
X732958Y522975D01*
X733333Y523100D01*
X733708Y523058D01*
X734083Y522892D01*
G01X731292Y521642D02*
X731000Y521933D01*
X730750Y522100D01*
X730417Y522183D01*
X730125Y522100D01*
X729917Y521933D01*
X729750Y521683D01*
X729708Y521392D01*
X729750Y521142D01*
X729917Y520892D01*
X730167Y520683D01*
X730458Y520600D01*
X730792Y520683D01*
X731083Y520933D01*
X731250Y521308D01*
X731292Y521725D01*
X731208Y522267D01*
X731083Y522558D01*
X730875Y522850D01*
X730583Y523058D01*
X730292Y523100D01*
X730000Y523017D01*
X729792Y522808D01*
G01X727500Y523100D02*
X727833Y523017D01*
X728083Y522808D01*
X728250Y522558D01*
X728375Y522225D01*
X728417Y521850D01*
X728375Y521475D01*
X728250Y521142D01*
X728083Y520892D01*
X727833Y520683D01*
X727500Y520600D01*
X727167Y520683D01*
X726917Y520892D01*
X726750Y521142D01*
X726625Y521475D01*
X726583Y521850D01*
X726625Y522225D01*
X726750Y522558D01*
X726917Y522808D01*
X727167Y523017D01*
X727500Y523100D01*
G01X739933Y546800D02*
Y549300D01*
X738892D01*
X738558Y549175D01*
X738350Y549008D01*
X738267Y548675D01*
X738350Y548342D01*
X738600Y548133D01*
X738892Y548008D01*
X739933D01*
G01X738892D02*
X738267Y546800D01*
G01X736892Y548883D02*
X736642Y549133D01*
X736350Y549258D01*
X736017Y549300D01*
X735600Y549217D01*
X735308Y549008D01*
X735225Y548758D01*
X735267Y548508D01*
X735433Y548300D01*
X736267Y547883D01*
X736642Y547592D01*
X736892Y547175D01*
X736975Y546800D01*
X735225D01*
G01X734017Y547175D02*
X733767Y546967D01*
X733475Y546842D01*
X733100Y546800D01*
X732725Y546883D01*
X732433Y547050D01*
X732225Y547342D01*
X732183Y547675D01*
X732267Y548008D01*
X732475Y548217D01*
X732767Y548383D01*
X733058Y548425D01*
X733350Y548383D01*
X733725Y548217D01*
X733600Y549300D01*
X732475D01*
G01X730100D02*
X730433Y549217D01*
X730683Y549008D01*
X730850Y548758D01*
X730975Y548425D01*
X731017Y548050D01*
X730975Y547675D01*
X730850Y547342D01*
X730683Y547092D01*
X730433Y546883D01*
X730100Y546800D01*
X729767Y546883D01*
X729517Y547092D01*
X729350Y547342D01*
X729225Y547675D01*
X729183Y548050D01*
X729225Y548425D01*
X729350Y548758D01*
X729517Y549008D01*
X729767Y549217D01*
X730100Y549300D01*
G01X739433Y541800D02*
Y544300D01*
X738392D01*
X738058Y544175D01*
X737850Y544008D01*
X737767Y543675D01*
X737850Y543342D01*
X738100Y543133D01*
X738392Y543008D01*
X739433D01*
G01X738392D02*
X737767Y541800D01*
G01X736392Y543883D02*
X736142Y544133D01*
X735850Y544258D01*
X735517Y544300D01*
X735100Y544217D01*
X734808Y544008D01*
X734725Y543758D01*
X734767Y543508D01*
X734933Y543300D01*
X735767Y542883D01*
X736142Y542592D01*
X736392Y542175D01*
X736475Y541800D01*
X734725D01*
G01X732100D02*
Y544300D01*
X733642Y542508D01*
X731558D01*
G01X730308Y542092D02*
X730017Y541883D01*
X729683Y541800D01*
X729350Y541883D01*
X729058Y542133D01*
X728850Y542508D01*
X728767Y542883D01*
Y543342D01*
X728850Y543717D01*
X729058Y544050D01*
X729308Y544217D01*
X729600Y544300D01*
X729933Y544217D01*
X730183Y544050D01*
X730350Y543800D01*
X730433Y543467D01*
X730350Y543175D01*
X730142Y542883D01*
X729892Y542717D01*
X729600Y542675D01*
X729267Y542758D01*
X729017Y542967D01*
X728767Y543342D01*
G01X714400Y492467D02*
X716900D01*
Y493508D01*
X716775Y493842D01*
X716608Y494050D01*
X716275Y494133D01*
X715942Y494050D01*
X715733Y493800D01*
X715608Y493508D01*
Y492467D01*
G01Y493508D02*
X714400Y494133D01*
G01Y496300D02*
X716900D01*
X716400Y495800D01*
G01X714400D02*
Y496800D01*
G01Y499800D02*
X716900D01*
X715108Y498258D01*
Y500342D01*
G01X714400Y502300D02*
X716900D01*
X716400Y501800D01*
G01X714400D02*
Y502800D01*
G01X723200Y492667D02*
X725700D01*
Y493708D01*
X725575Y494042D01*
X725408Y494250D01*
X725075Y494333D01*
X724742Y494250D01*
X724533Y494000D01*
X724408Y493708D01*
Y492667D01*
G01Y493708D02*
X723200Y494333D01*
G01Y496500D02*
X725700D01*
X725200Y496000D01*
G01X723200D02*
Y497000D01*
G01Y500000D02*
X725700D01*
X723908Y498458D01*
Y500542D01*
G01X725700Y502500D02*
X725617Y502167D01*
X725408Y501917D01*
X725158Y501750D01*
X724825Y501625D01*
X724450Y501583D01*
X724075Y501625D01*
X723742Y501750D01*
X723492Y501917D01*
X723283Y502167D01*
X723200Y502500D01*
X723283Y502833D01*
X723492Y503083D01*
X723742Y503250D01*
X724075Y503375D01*
X724450Y503417D01*
X724825Y503375D01*
X725158Y503250D01*
X725408Y503083D01*
X725617Y502833D01*
X725700Y502500D01*
G01X719000Y492667D02*
X721500D01*
Y493708D01*
X721375Y494042D01*
X721208Y494250D01*
X720875Y494333D01*
X720542Y494250D01*
X720333Y494000D01*
X720208Y493708D01*
Y492667D01*
G01Y493708D02*
X719000Y494333D01*
G01Y496500D02*
X721500D01*
X721000Y496000D01*
G01X719000D02*
Y497000D01*
G01X721083Y498708D02*
X721333Y498958D01*
X721458Y499250D01*
X721500Y499583D01*
X721417Y500000D01*
X721208Y500292D01*
X720958Y500375D01*
X720708Y500333D01*
X720500Y500167D01*
X720083Y499333D01*
X719792Y498958D01*
X719375Y498708D01*
X719000Y498625D01*
Y500375D01*
G01X721500Y502500D02*
X721417Y502167D01*
X721208Y501917D01*
X720958Y501750D01*
X720625Y501625D01*
X720250Y501583D01*
X719875Y501625D01*
X719542Y501750D01*
X719292Y501917D01*
X719083Y502167D01*
X719000Y502500D01*
X719083Y502833D01*
X719292Y503083D01*
X719542Y503250D01*
X719875Y503375D01*
X720250Y503417D01*
X720625Y503375D01*
X720958Y503250D01*
X721208Y503083D01*
X721417Y502833D01*
X721500Y502500D01*
G01X731800Y492567D02*
X734300D01*
Y493608D01*
X734175Y493942D01*
X734008Y494150D01*
X733675Y494233D01*
X733342Y494150D01*
X733133Y493900D01*
X733008Y493608D01*
Y492567D01*
G01Y493608D02*
X731800Y494233D01*
G01Y496400D02*
X734300D01*
X733800Y495900D01*
G01X731800D02*
Y496900D01*
G01Y499400D02*
X734300D01*
X733800Y498900D01*
G01X731800D02*
Y499900D01*
G01X732092Y501692D02*
X731883Y501983D01*
X731800Y502317D01*
X731883Y502650D01*
X732133Y502942D01*
X732508Y503150D01*
X732883Y503233D01*
X733342D01*
X733717Y503150D01*
X734050Y502942D01*
X734217Y502692D01*
X734300Y502400D01*
X734217Y502067D01*
X734050Y501817D01*
X733800Y501650D01*
X733467Y501567D01*
X733175Y501650D01*
X732883Y501858D01*
X732717Y502108D01*
X732675Y502400D01*
X732758Y502733D01*
X732967Y502983D01*
X733342Y503233D01*
G01X727300Y492767D02*
X729800D01*
Y493808D01*
X729675Y494142D01*
X729508Y494350D01*
X729175Y494433D01*
X728842Y494350D01*
X728633Y494100D01*
X728508Y493808D01*
Y492767D01*
G01Y493808D02*
X727300Y494433D01*
G01Y496600D02*
X729800D01*
X729300Y496100D01*
G01X727300D02*
Y497100D01*
G01Y499600D02*
X729800D01*
X729300Y499100D01*
G01X727300D02*
Y500100D01*
G01Y502600D02*
X727342Y502892D01*
X727467Y503225D01*
X727675Y503433D01*
X727967Y503517D01*
X728258Y503433D01*
X728508Y503183D01*
X728633Y502808D01*
Y502392D01*
X728717Y502142D01*
X728925Y501933D01*
X729217Y501850D01*
X729508Y501975D01*
X729717Y502267D01*
X729800Y502600D01*
X729717Y502933D01*
X729508Y503225D01*
X729217Y503350D01*
X728925Y503267D01*
X728717Y503058D01*
X728633Y502808D01*
Y502392D01*
X728508Y502017D01*
X728258Y501767D01*
X727967Y501683D01*
X727675Y501767D01*
X727467Y501975D01*
X727342Y502308D01*
X727300Y502600D01*
G01X744433Y534400D02*
Y536900D01*
X743392D01*
X743058Y536775D01*
X742850Y536608D01*
X742767Y536275D01*
X742850Y535942D01*
X743100Y535733D01*
X743392Y535608D01*
X744433D01*
G01X743392D02*
X742767Y534400D01*
G01X741392Y536483D02*
X741142Y536733D01*
X740850Y536858D01*
X740517Y536900D01*
X740100Y536817D01*
X739808Y536608D01*
X739725Y536358D01*
X739767Y536108D01*
X739933Y535900D01*
X740767Y535483D01*
X741142Y535192D01*
X741392Y534775D01*
X741475Y534400D01*
X739725D01*
G01X737100D02*
Y536900D01*
X738642Y535108D01*
X736558D01*
G01X734600Y534400D02*
X734308Y534442D01*
X733975Y534567D01*
X733767Y534775D01*
X733683Y535067D01*
X733767Y535358D01*
X734017Y535608D01*
X734392Y535733D01*
X734808D01*
X735058Y535817D01*
X735267Y536025D01*
X735350Y536317D01*
X735225Y536608D01*
X734933Y536817D01*
X734600Y536900D01*
X734267Y536817D01*
X733975Y536608D01*
X733850Y536317D01*
X733933Y536025D01*
X734142Y535817D01*
X734392Y535733D01*
X734808D01*
X735183Y535608D01*
X735433Y535358D01*
X735517Y535067D01*
X735433Y534775D01*
X735225Y534567D01*
X734892Y534442D01*
X734600Y534400D01*
G01X722000Y560783D02*
X720208D01*
X719833Y560950D01*
X719583Y561283D01*
X719500Y561700D01*
X719583Y562117D01*
X719833Y562450D01*
X720208Y562617D01*
X722000D01*
G01X719500Y564700D02*
X722000D01*
X721500Y564200D01*
G01X719500D02*
Y565200D01*
G01X720542Y566908D02*
X720833Y567200D01*
X721000Y567450D01*
X721083Y567783D01*
X721000Y568075D01*
X720833Y568283D01*
X720583Y568450D01*
X720292Y568492D01*
X720042Y568450D01*
X719792Y568283D01*
X719583Y568033D01*
X719500Y567742D01*
X719583Y567408D01*
X719833Y567117D01*
X720208Y566950D01*
X720625Y566908D01*
X721167Y566992D01*
X721458Y567117D01*
X721750Y567325D01*
X721958Y567617D01*
X722000Y567908D01*
X721917Y568200D01*
X721708Y568408D01*
G01X727092Y565617D02*
X727217Y565367D01*
X727300Y565075D01*
Y564742D01*
X727175Y564367D01*
X726967Y564075D01*
X726717Y563867D01*
X726300Y563700D01*
X725925Y563658D01*
X725550Y563742D01*
X725300Y563867D01*
X725050Y564117D01*
X724883Y564408D01*
X724800Y564700D01*
Y564992D01*
X724883Y565283D01*
X725008Y565533D01*
X725175Y565742D01*
G01X726883Y566908D02*
X727133Y567158D01*
X727258Y567450D01*
X727300Y567783D01*
X727217Y568200D01*
X727008Y568492D01*
X726758Y568575D01*
X726508Y568533D01*
X726300Y568367D01*
X725883Y567533D01*
X725592Y567158D01*
X725175Y566908D01*
X724800Y566825D01*
Y568575D01*
G01X725175Y569783D02*
X724967Y570033D01*
X724842Y570325D01*
X724800Y570700D01*
X724883Y571075D01*
X725050Y571367D01*
X725342Y571575D01*
X725675Y571617D01*
X726008Y571533D01*
X726217Y571325D01*
X726383Y571033D01*
X726425Y570742D01*
X726383Y570450D01*
X726217Y570075D01*
X727300Y570200D01*
Y571325D01*
G01X724800Y573700D02*
X727300D01*
X726800Y573200D01*
G01X724800D02*
Y574200D01*
G01X755433Y579200D02*
Y581700D01*
X754392D01*
X754058Y581575D01*
X753850Y581408D01*
X753767Y581075D01*
X753850Y580742D01*
X754100Y580533D01*
X754392Y580408D01*
X755433D01*
G01X754392D02*
X753767Y579200D01*
G01X752517Y579700D02*
X752267Y579408D01*
X751933Y579242D01*
X751558Y579200D01*
X751225Y579242D01*
X750892Y579450D01*
X750683Y579700D01*
X750642Y579950D01*
X750725Y580242D01*
X751017Y580450D01*
X751308Y580533D01*
X751683D01*
G01X751308D02*
X751058Y580658D01*
X750850Y580867D01*
X750767Y581117D01*
X750850Y581367D01*
X751058Y581575D01*
X751433Y581700D01*
X751808Y581658D01*
X752183Y581492D01*
G01X749517Y579575D02*
X749267Y579367D01*
X748975Y579242D01*
X748600Y579200D01*
X748225Y579283D01*
X747933Y579450D01*
X747725Y579742D01*
X747683Y580075D01*
X747767Y580408D01*
X747975Y580617D01*
X748267Y580783D01*
X748558Y580825D01*
X748850Y580783D01*
X749225Y580617D01*
X749100Y581700D01*
X747975D01*
G01X746392Y580242D02*
X746100Y580533D01*
X745850Y580700D01*
X745517Y580783D01*
X745225Y580700D01*
X745017Y580533D01*
X744850Y580283D01*
X744808Y579992D01*
X744850Y579742D01*
X745017Y579492D01*
X745267Y579283D01*
X745558Y579200D01*
X745892Y579283D01*
X746183Y579533D01*
X746350Y579908D01*
X746392Y580325D01*
X746308Y580867D01*
X746183Y581158D01*
X745975Y581450D01*
X745683Y581658D01*
X745392Y581700D01*
X745100Y581617D01*
X744892Y581408D01*
G01X755533Y574800D02*
Y577300D01*
X754492D01*
X754158Y577175D01*
X753950Y577008D01*
X753867Y576675D01*
X753950Y576342D01*
X754200Y576133D01*
X754492Y576008D01*
X755533D01*
G01X754492D02*
X753867Y574800D01*
G01X752617Y575300D02*
X752367Y575008D01*
X752033Y574842D01*
X751658Y574800D01*
X751325Y574842D01*
X750992Y575050D01*
X750783Y575300D01*
X750742Y575550D01*
X750825Y575842D01*
X751117Y576050D01*
X751408Y576133D01*
X751783D01*
G01X751408D02*
X751158Y576258D01*
X750950Y576467D01*
X750867Y576717D01*
X750950Y576967D01*
X751158Y577175D01*
X751533Y577300D01*
X751908Y577258D01*
X752283Y577092D01*
G01X749617Y575175D02*
X749367Y574967D01*
X749075Y574842D01*
X748700Y574800D01*
X748325Y574883D01*
X748033Y575050D01*
X747825Y575342D01*
X747783Y575675D01*
X747867Y576008D01*
X748075Y576217D01*
X748367Y576383D01*
X748658Y576425D01*
X748950Y576383D01*
X749325Y576217D01*
X749200Y577300D01*
X748075D01*
G01X746617Y575175D02*
X746367Y574967D01*
X746075Y574842D01*
X745700Y574800D01*
X745325Y574883D01*
X745033Y575050D01*
X744825Y575342D01*
X744783Y575675D01*
X744867Y576008D01*
X745075Y576217D01*
X745367Y576383D01*
X745658Y576425D01*
X745950Y576383D01*
X746325Y576217D01*
X746200Y577300D01*
X745075D01*
G01X755833Y570400D02*
Y572900D01*
X754792D01*
X754458Y572775D01*
X754250Y572608D01*
X754167Y572275D01*
X754250Y571942D01*
X754500Y571733D01*
X754792Y571608D01*
X755833D01*
G01X754792D02*
X754167Y570400D01*
G01X752917Y570900D02*
X752667Y570608D01*
X752333Y570442D01*
X751958Y570400D01*
X751625Y570442D01*
X751292Y570650D01*
X751083Y570900D01*
X751042Y571150D01*
X751125Y571442D01*
X751417Y571650D01*
X751708Y571733D01*
X752083D01*
G01X751708D02*
X751458Y571858D01*
X751250Y572067D01*
X751167Y572317D01*
X751250Y572567D01*
X751458Y572775D01*
X751833Y572900D01*
X752208Y572858D01*
X752583Y572692D01*
G01X749917Y570775D02*
X749667Y570567D01*
X749375Y570442D01*
X749000Y570400D01*
X748625Y570483D01*
X748333Y570650D01*
X748125Y570942D01*
X748083Y571275D01*
X748167Y571608D01*
X748375Y571817D01*
X748667Y571983D01*
X748958Y572025D01*
X749250Y571983D01*
X749625Y571817D01*
X749500Y572900D01*
X748375D01*
G01X745500Y570400D02*
Y572900D01*
X747042Y571108D01*
X744958D01*
G01X755533Y566600D02*
Y569100D01*
X754492D01*
X754158Y568975D01*
X753950Y568808D01*
X753867Y568475D01*
X753950Y568142D01*
X754200Y567933D01*
X754492Y567808D01*
X755533D01*
G01X754492D02*
X753867Y566600D01*
G01X752617Y567100D02*
X752367Y566808D01*
X752033Y566642D01*
X751658Y566600D01*
X751325Y566642D01*
X750992Y566850D01*
X750783Y567100D01*
X750742Y567350D01*
X750825Y567642D01*
X751117Y567850D01*
X751408Y567933D01*
X751783D01*
G01X751408D02*
X751158Y568058D01*
X750950Y568267D01*
X750867Y568517D01*
X750950Y568767D01*
X751158Y568975D01*
X751533Y569100D01*
X751908Y569058D01*
X752283Y568892D01*
G01X749617Y566975D02*
X749367Y566767D01*
X749075Y566642D01*
X748700Y566600D01*
X748325Y566683D01*
X748033Y566850D01*
X747825Y567142D01*
X747783Y567475D01*
X747867Y567808D01*
X748075Y568017D01*
X748367Y568183D01*
X748658Y568225D01*
X748950Y568183D01*
X749325Y568017D01*
X749200Y569100D01*
X748075D01*
G01X746617Y567100D02*
X746367Y566808D01*
X746033Y566642D01*
X745658Y566600D01*
X745325Y566642D01*
X744992Y566850D01*
X744783Y567100D01*
X744742Y567350D01*
X744825Y567642D01*
X745117Y567850D01*
X745408Y567933D01*
X745783D01*
G01X745408D02*
X745158Y568058D01*
X744950Y568267D01*
X744867Y568517D01*
X744950Y568767D01*
X745158Y568975D01*
X745533Y569100D01*
X745908Y569058D01*
X746283Y568892D01*
G01X755148Y849186D02*
Y851686D01*
X754107D01*
X753773Y851561D01*
X753565Y851394D01*
X753482Y851061D01*
X753565Y850728D01*
X753815Y850519D01*
X754107Y850394D01*
X755148D01*
G01X754107D02*
X753482Y849186D01*
G01X751315D02*
Y851686D01*
X751815Y851186D01*
G01Y849186D02*
X750815D01*
G01X748315D02*
Y851686D01*
X748815Y851186D01*
G01Y849186D02*
X747815D01*
G01X745315D02*
Y851686D01*
X745815Y851186D01*
G01Y849186D02*
X744815D01*
G01X755202Y844405D02*
Y846905D01*
X754161D01*
X753827Y846780D01*
X753619Y846613D01*
X753536Y846280D01*
X753619Y845947D01*
X753869Y845738D01*
X754161Y845613D01*
X755202D01*
G01X754161D02*
X753536Y844405D01*
G01X751369D02*
Y846905D01*
X751869Y846405D01*
G01Y844405D02*
X750869D01*
G01X748369Y846905D02*
X748702Y846822D01*
X748952Y846613D01*
X749119Y846363D01*
X749244Y846030D01*
X749286Y845655D01*
X749244Y845280D01*
X749119Y844947D01*
X748952Y844697D01*
X748702Y844488D01*
X748369Y844405D01*
X748036Y844488D01*
X747786Y844697D01*
X747619Y844947D01*
X747494Y845280D01*
X747452Y845655D01*
X747494Y846030D01*
X747619Y846363D01*
X747786Y846613D01*
X748036Y846822D01*
X748369Y846905D01*
G01X746077Y844697D02*
X745786Y844488D01*
X745452Y844405D01*
X745119Y844488D01*
X744827Y844738D01*
X744619Y845113D01*
X744536Y845488D01*
Y845947D01*
X744619Y846322D01*
X744827Y846655D01*
X745077Y846822D01*
X745369Y846905D01*
X745702Y846822D01*
X745952Y846655D01*
X746119Y846405D01*
X746202Y846072D01*
X746119Y845780D01*
X745911Y845488D01*
X745661Y845322D01*
X745369Y845280D01*
X745036Y845363D01*
X744786Y845572D01*
X744536Y845947D01*
G01X757333Y853300D02*
Y855800D01*
X756292D01*
X755958Y855675D01*
X755750Y855508D01*
X755667Y855175D01*
X755750Y854842D01*
X756000Y854633D01*
X756292Y854508D01*
X757333D01*
G01X756292D02*
X755667Y853300D01*
G01X754292Y855383D02*
X754042Y855633D01*
X753750Y855758D01*
X753417Y855800D01*
X753000Y855717D01*
X752708Y855508D01*
X752625Y855258D01*
X752667Y855008D01*
X752833Y854800D01*
X753667Y854383D01*
X754042Y854092D01*
X754292Y853675D01*
X754375Y853300D01*
X752625D01*
G01X751208Y853592D02*
X750917Y853383D01*
X750583Y853300D01*
X750250Y853383D01*
X749958Y853633D01*
X749750Y854008D01*
X749667Y854383D01*
Y854842D01*
X749750Y855217D01*
X749958Y855550D01*
X750208Y855717D01*
X750500Y855800D01*
X750833Y855717D01*
X751083Y855550D01*
X751250Y855300D01*
X751333Y854967D01*
X751250Y854675D01*
X751042Y854383D01*
X750792Y854217D01*
X750500Y854175D01*
X750167Y854258D01*
X749917Y854467D01*
X749667Y854842D01*
G01X747500Y853300D02*
X747208Y853342D01*
X746875Y853467D01*
X746667Y853675D01*
X746583Y853967D01*
X746667Y854258D01*
X746917Y854508D01*
X747292Y854633D01*
X747708D01*
X747958Y854717D01*
X748167Y854925D01*
X748250Y855217D01*
X748125Y855508D01*
X747833Y855717D01*
X747500Y855800D01*
X747167Y855717D01*
X746875Y855508D01*
X746750Y855217D01*
X746833Y854925D01*
X747042Y854717D01*
X747292Y854633D01*
X747708D01*
X748083Y854508D01*
X748333Y854258D01*
X748417Y853967D01*
X748333Y853675D01*
X748125Y853467D01*
X747792Y853342D01*
X747500Y853300D01*
G01X744833Y863300D02*
Y865800D01*
X743792D01*
X743458Y865675D01*
X743250Y865508D01*
X743167Y865175D01*
X743250Y864842D01*
X743500Y864633D01*
X743792Y864508D01*
X744833D01*
G01X743792D02*
X743167Y863300D01*
G01X741792Y865383D02*
X741542Y865633D01*
X741250Y865758D01*
X740917Y865800D01*
X740500Y865717D01*
X740208Y865508D01*
X740125Y865258D01*
X740167Y865008D01*
X740333Y864800D01*
X741167Y864383D01*
X741542Y864092D01*
X741792Y863675D01*
X741875Y863300D01*
X740125D01*
G01X738708Y863592D02*
X738417Y863383D01*
X738083Y863300D01*
X737750Y863383D01*
X737458Y863633D01*
X737250Y864008D01*
X737167Y864383D01*
Y864842D01*
X737250Y865217D01*
X737458Y865550D01*
X737708Y865717D01*
X738000Y865800D01*
X738333Y865717D01*
X738583Y865550D01*
X738750Y865300D01*
X738833Y864967D01*
X738750Y864675D01*
X738542Y864383D01*
X738292Y864217D01*
X738000Y864175D01*
X737667Y864258D01*
X737417Y864467D01*
X737167Y864842D01*
G01X735708Y863592D02*
X735417Y863383D01*
X735083Y863300D01*
X734750Y863383D01*
X734458Y863633D01*
X734250Y864008D01*
X734167Y864383D01*
Y864842D01*
X734250Y865217D01*
X734458Y865550D01*
X734708Y865717D01*
X735000Y865800D01*
X735333Y865717D01*
X735583Y865550D01*
X735750Y865300D01*
X735833Y864967D01*
X735750Y864675D01*
X735542Y864383D01*
X735292Y864217D01*
X735000Y864175D01*
X734667Y864258D01*
X734417Y864467D01*
X734167Y864842D01*
G54D17*
G01X-755164Y-252763D02*
Y-235263D01*
G01X-746868D02*
X-755164Y-246055D01*
G01X-745558Y-252763D02*
X-751453Y-241097D01*
G01X-737883Y-252763D02*
Y-235263D01*
X-727839Y-252763D01*
Y-235263D01*
G01X-715361Y-252763D02*
X-717108Y-252471D01*
X-718636Y-251305D01*
X-719946Y-249555D01*
X-720820Y-247513D01*
X-721256Y-245180D01*
Y-242846D01*
X-720820Y-240513D01*
X-719946Y-238471D01*
X-718636Y-236722D01*
X-717108Y-235555D01*
X-715361Y-235263D01*
X-713615Y-235555D01*
X-712086Y-236722D01*
X-710776Y-238471D01*
X-709902Y-240513D01*
X-709466Y-242846D01*
Y-245180D01*
X-709902Y-247513D01*
X-710776Y-249555D01*
X-712086Y-251305D01*
X-713615Y-252471D01*
X-715361Y-252763D01*
G01X-702446D02*
X-693276Y-235263D01*
G01X-702446D02*
X-693276Y-252763D01*
G01X-658494D02*
X-667228D01*
Y-235263D01*
X-658494D01*
G01X-661988Y-243721D02*
X-667228D01*
G01X-649946Y-252763D02*
X-640776Y-235263D01*
G01X-649946D02*
X-640776Y-252763D01*
G01X-632228D02*
Y-235263D01*
X-626988D01*
X-625241Y-236138D01*
X-623931Y-238180D01*
X-623494Y-240513D01*
X-623931Y-242846D01*
X-625023Y-244596D01*
X-626988Y-245472D01*
X-632228D01*
G01X-615820Y-252763D02*
X-610361Y-235263D01*
X-604902Y-252763D01*
G01X-606868Y-246638D02*
X-613855D01*
G01X-597883Y-252763D02*
Y-235263D01*
X-587839Y-252763D01*
Y-235263D01*
G01X-580164Y-252763D02*
Y-235263D01*
X-575798D01*
X-574051Y-236138D01*
X-572741Y-237305D01*
X-571649Y-239054D01*
X-570776Y-241097D01*
X-570558Y-244013D01*
X-570776Y-246930D01*
X-571649Y-248972D01*
X-572741Y-250722D01*
X-574051Y-251888D01*
X-575798Y-252763D01*
X-580164D01*
G01X-553494D02*
X-562228D01*
Y-235263D01*
X-553494D01*
G01X-556988Y-243721D02*
X-562228D01*
G01X-544728Y-252763D02*
Y-235263D01*
X-539269D01*
X-537523Y-236138D01*
X-536431Y-237305D01*
X-535994Y-239638D01*
X-536431Y-241972D01*
X-537741Y-243430D01*
X-539269Y-244305D01*
X-544728D01*
G01X-539269D02*
X-535994Y-252763D01*
G01X-503615Y-243430D02*
X-502741Y-242555D01*
X-502086Y-241097D01*
X-501649Y-239054D01*
X-502086Y-237305D01*
X-502959Y-236138D01*
X-504488Y-235263D01*
X-510383D01*
Y-252763D01*
X-503178D01*
X-501649Y-251597D01*
X-500776Y-249846D01*
X-500339Y-247805D01*
X-500776Y-245763D01*
X-502086Y-244013D01*
X-503615Y-243430D01*
X-510383D01*
G01X-487861Y-252763D02*
X-489608Y-252471D01*
X-491136Y-251305D01*
X-492446Y-249555D01*
X-493320Y-247513D01*
X-493756Y-245180D01*
Y-242846D01*
X-493320Y-240513D01*
X-492446Y-238471D01*
X-491136Y-236722D01*
X-489608Y-235555D01*
X-487861Y-235263D01*
X-486115Y-235555D01*
X-484586Y-236722D01*
X-483276Y-238471D01*
X-482402Y-240513D01*
X-481966Y-242846D01*
Y-245180D01*
X-482402Y-247513D01*
X-483276Y-249555D01*
X-484586Y-251305D01*
X-486115Y-252471D01*
X-487861Y-252763D01*
G01X-475820D02*
X-470361Y-235263D01*
X-464902Y-252763D01*
G01X-466868Y-246638D02*
X-473855D01*
G01X-457228Y-252763D02*
Y-235263D01*
X-451769D01*
X-450023Y-236138D01*
X-448931Y-237305D01*
X-448494Y-239638D01*
X-448931Y-241972D01*
X-450241Y-243430D01*
X-451769Y-244305D01*
X-457228D01*
G01X-451769D02*
X-448494Y-252763D01*
G01X-440164D02*
Y-235263D01*
X-435798D01*
X-434051Y-236138D01*
X-432741Y-237305D01*
X-431649Y-239054D01*
X-430776Y-241097D01*
X-430558Y-244013D01*
X-430776Y-246930D01*
X-431649Y-248972D01*
X-432741Y-250722D01*
X-434051Y-251888D01*
X-435798Y-252763D01*
X-440164D01*
G01X-633538Y-207763D02*
Y-190263D01*
X-627861Y-204846D01*
X-622184Y-190263D01*
Y-207763D01*
G01X-610361D02*
X-611671Y-207471D01*
X-612981Y-206305D01*
X-613855Y-204263D01*
X-614291Y-201930D01*
X-613855Y-199596D01*
X-612981Y-197555D01*
X-611671Y-196388D01*
X-610361Y-196097D01*
X-609051Y-196388D01*
X-607741Y-197555D01*
X-606868Y-199596D01*
X-606649Y-201930D01*
X-606868Y-204263D01*
X-607741Y-206305D01*
X-609051Y-207471D01*
X-610361Y-207763D01*
G01X-588931Y-190263D02*
Y-207763D01*
G01Y-205139D02*
X-589804Y-206597D01*
X-591115Y-207471D01*
X-592643Y-207763D01*
X-594389Y-207180D01*
X-595699Y-205722D01*
X-596573Y-203972D01*
X-596791Y-201930D01*
X-596573Y-199888D01*
X-595699Y-198138D01*
X-594389Y-196680D01*
X-592643Y-196097D01*
X-591115Y-196388D01*
X-590023Y-196972D01*
X-588931Y-198138D01*
G01X-578636Y-199888D02*
X-571649D01*
X-572304Y-197846D01*
X-573396Y-196680D01*
X-574924Y-196097D01*
X-576453Y-196388D01*
X-577763Y-197263D01*
X-578636Y-199305D01*
X-579073Y-201055D01*
Y-202805D01*
X-578636Y-204555D01*
X-577544Y-206305D01*
X-576234Y-207471D01*
X-574706Y-207763D01*
X-573178Y-207180D01*
X-571649Y-205430D01*
G01X-557861Y-207763D02*
Y-190263D01*
G01X-380161Y-252763D02*
Y-235263D01*
X-382781Y-238763D01*
G01Y-252763D02*
X-377541D01*
G01X-366809Y-238180D02*
X-365499Y-236430D01*
X-363971Y-235555D01*
X-362224Y-235263D01*
X-360041Y-235846D01*
X-358513Y-237305D01*
X-358076Y-239054D01*
X-358294Y-240805D01*
X-359168Y-242263D01*
X-363534Y-245180D01*
X-365499Y-247221D01*
X-366809Y-250139D01*
X-367246Y-252763D01*
X-358076D01*
G01X-345161Y-235263D02*
X-346908Y-235846D01*
X-348218Y-237305D01*
X-349091Y-239054D01*
X-349746Y-241388D01*
X-349964Y-244013D01*
X-349746Y-246638D01*
X-349091Y-248972D01*
X-348218Y-250722D01*
X-346908Y-252180D01*
X-345161Y-252763D01*
X-343415Y-252180D01*
X-342104Y-250722D01*
X-341231Y-248972D01*
X-340576Y-246638D01*
X-340358Y-244013D01*
X-340576Y-241388D01*
X-341231Y-239054D01*
X-342104Y-237305D01*
X-343415Y-235846D01*
X-345161Y-235263D01*
G01X-327661D02*
X-329408Y-235846D01*
X-330718Y-237305D01*
X-331591Y-239054D01*
X-332246Y-241388D01*
X-332464Y-244013D01*
X-332246Y-246638D01*
X-331591Y-248972D01*
X-330718Y-250722D01*
X-329408Y-252180D01*
X-327661Y-252763D01*
X-325915Y-252180D01*
X-324604Y-250722D01*
X-323731Y-248972D01*
X-323076Y-246638D01*
X-322858Y-244013D01*
X-323076Y-241388D01*
X-323731Y-239054D01*
X-324604Y-237305D01*
X-325915Y-235846D01*
X-327661Y-235263D01*
G01X-307541Y-252763D02*
Y-235263D01*
X-315620Y-247805D01*
X-304702D01*
G01X-393278Y-207763D02*
Y-190263D01*
X-388038D01*
X-386291Y-191138D01*
X-384981Y-193180D01*
X-384544Y-195513D01*
X-384981Y-197846D01*
X-386073Y-199596D01*
X-388038Y-200472D01*
X-393278D01*
G01X-366608Y-191722D02*
X-367918Y-190846D01*
X-369446Y-190263D01*
X-371193D01*
X-373158Y-191138D01*
X-374686Y-192596D01*
X-375778Y-194347D01*
X-376651Y-197263D01*
X-376870Y-199888D01*
X-376433Y-202513D01*
X-375778Y-204263D01*
X-374468Y-206013D01*
X-372939Y-207180D01*
X-371411Y-207763D01*
X-369883D01*
X-368354Y-207180D01*
X-367044Y-206305D01*
X-365952Y-205139D01*
G01X-352165Y-198430D02*
X-351291Y-197555D01*
X-350636Y-196097D01*
X-350199Y-194054D01*
X-350636Y-192305D01*
X-351509Y-191138D01*
X-353038Y-190263D01*
X-358933D01*
Y-207763D01*
X-351728D01*
X-350199Y-206597D01*
X-349326Y-204846D01*
X-348889Y-202805D01*
X-349326Y-200763D01*
X-350636Y-199013D01*
X-352165Y-198430D01*
X-358933D01*
G01X-342961Y-213596D02*
X-329861D01*
G01X-323933Y-207763D02*
Y-190263D01*
X-313889Y-207763D01*
Y-190263D01*
G01X-301411Y-207763D02*
X-303158Y-207471D01*
X-304686Y-206305D01*
X-305996Y-204555D01*
X-306870Y-202513D01*
X-307306Y-200180D01*
Y-197846D01*
X-306870Y-195513D01*
X-305996Y-193471D01*
X-304686Y-191722D01*
X-303158Y-190555D01*
X-301411Y-190263D01*
X-299665Y-190555D01*
X-298136Y-191722D01*
X-296826Y-193471D01*
X-295952Y-195513D01*
X-295516Y-197846D01*
Y-200180D01*
X-295952Y-202513D01*
X-296826Y-204555D01*
X-298136Y-206305D01*
X-299665Y-207471D01*
X-301411Y-207763D01*
G01X-218861Y-252763D02*
Y-235263D01*
X-221481Y-238763D01*
G01Y-252763D02*
X-216241D01*
G01X-250570Y-190263D02*
X-245111Y-207763D01*
X-239652Y-190263D01*
G01X-223244Y-207763D02*
X-231978D01*
Y-190263D01*
X-223244D01*
G01X-226738Y-198721D02*
X-231978D01*
G01X-214478Y-207763D02*
Y-190263D01*
X-209019D01*
X-207273Y-191138D01*
X-206181Y-192305D01*
X-205744Y-194638D01*
X-206181Y-196972D01*
X-207491Y-198430D01*
X-209019Y-199305D01*
X-214478D01*
G01X-209019D02*
X-205744Y-207763D01*
G01X-192611Y-208346D02*
X-193048Y-208055D01*
Y-207471D01*
X-192611Y-207180D01*
X-192174Y-207471D01*
Y-208055D01*
X-192611Y-208346D01*
G01X-44407Y-243430D02*
X-45281Y-242555D01*
X-45936Y-241097D01*
X-46373Y-239054D01*
X-45936Y-237305D01*
X-45063Y-236138D01*
X-43534Y-235263D01*
X-37639D01*
Y-252763D01*
X-44844D01*
X-46373Y-251597D01*
X-47246Y-249846D01*
X-47683Y-247805D01*
X-47246Y-245763D01*
X-45936Y-244013D01*
X-44407Y-243430D01*
X-37639D01*
G01X-55576Y-250430D02*
X-57323Y-251888D01*
X-59288Y-252763D01*
X-61034D01*
X-62781Y-251888D01*
X-64091Y-250430D01*
X-64746Y-248388D01*
X-64309Y-246347D01*
X-63218Y-244596D01*
X-61253Y-243430D01*
X-58633Y-242846D01*
X-57104Y-241680D01*
X-56449Y-239638D01*
X-56886Y-237596D01*
X-57978Y-236138D01*
X-59506Y-235263D01*
X-61034D01*
X-62563Y-235846D01*
X-63873Y-237305D01*
G01X-75041Y-235263D02*
X-80281D01*
G01X-77661D02*
Y-252763D01*
G01X-75041D02*
X-80281D01*
G01X-90794Y-235263D02*
Y-252763D01*
X-99528D01*
G01X-107858D02*
Y-235263D01*
G01X-116154D02*
X-107858Y-246055D01*
G01X-117464Y-252763D02*
X-111569Y-241097D01*
G01X-125778Y-190263D02*
Y-207763D01*
X-117044D01*
G01X-99981D02*
Y-196097D01*
G01Y-198138D02*
X-100854Y-196972D01*
X-102165Y-196388D01*
X-103693Y-196097D01*
X-105221Y-196680D01*
X-106531Y-197846D01*
X-107405Y-199596D01*
X-107841Y-201930D01*
X-107405Y-204263D01*
X-106531Y-206013D01*
X-105221Y-207180D01*
X-103693Y-207763D01*
X-102165Y-207471D01*
X-100854Y-206597D01*
X-99981Y-205430D01*
G01X-90996Y-213013D02*
X-89686Y-213596D01*
X-87939Y-213013D01*
X-86848Y-211847D01*
X-85974Y-210388D01*
X-84665Y-205722D01*
X-81826Y-196097D01*
G01X-88813D02*
X-84665Y-205722D01*
G01X-72186Y-199888D02*
X-65199D01*
X-65854Y-197846D01*
X-66946Y-196680D01*
X-68474Y-196097D01*
X-70003Y-196388D01*
X-71313Y-197263D01*
X-72186Y-199305D01*
X-72623Y-201055D01*
Y-202805D01*
X-72186Y-204555D01*
X-71094Y-206305D01*
X-69784Y-207471D01*
X-68256Y-207763D01*
X-66728Y-207180D01*
X-65199Y-205430D01*
G01X-54468Y-207763D02*
Y-196097D01*
G01Y-198430D02*
X-53376Y-197263D01*
X-52284Y-196388D01*
X-50756Y-196097D01*
X-49665Y-196388D01*
X-48354Y-197263D01*
G01X-37186Y-205722D02*
X-36094Y-206888D01*
X-34566Y-207763D01*
X-33256D01*
X-31946Y-207180D01*
X-31073Y-206305D01*
X-30636Y-205139D01*
X-30854Y-203388D01*
X-31728Y-202513D01*
X-35658Y-200763D01*
X-36531Y-198721D01*
X-36094Y-197263D01*
X-35221Y-196388D01*
X-33911Y-196097D01*
X-32601Y-196388D01*
X-31291Y-197263D01*
G01X51772Y-235263D02*
Y-252763D01*
X60506D01*
G01X68836Y-235263D02*
Y-247805D01*
X69709Y-250430D01*
X71456Y-252180D01*
X73639Y-252763D01*
X75822Y-252180D01*
X77569Y-250430D01*
X78442Y-247805D01*
Y-235263D01*
G01X95942Y-236722D02*
X94632Y-235846D01*
X93104Y-235263D01*
X91357D01*
X89392Y-236138D01*
X87864Y-237596D01*
X86772Y-239347D01*
X85899Y-242263D01*
X85680Y-244888D01*
X86117Y-247513D01*
X86772Y-249263D01*
X88082Y-251013D01*
X89611Y-252180D01*
X91139Y-252763D01*
X92667D01*
X94196Y-252180D01*
X95506Y-251305D01*
X96598Y-250139D01*
G01X103836Y-252763D02*
Y-235263D01*
G01X112132D02*
X103836Y-246055D01*
G01X113442Y-252763D02*
X107547Y-241097D01*
G01X126139Y-252763D02*
Y-244888D01*
X121772Y-235263D01*
G01X130506D02*
X126139Y-244888D01*
G01X25086Y-207763D02*
Y-190263D01*
X29452D01*
X31199Y-191138D01*
X32509Y-192305D01*
X33601Y-194054D01*
X34474Y-196097D01*
X34692Y-199013D01*
X34474Y-201930D01*
X33601Y-203972D01*
X32509Y-205722D01*
X31199Y-206888D01*
X29452Y-207763D01*
X25086D01*
G01X44114Y-199888D02*
X51101D01*
X50446Y-197846D01*
X49354Y-196680D01*
X47826Y-196097D01*
X46297Y-196388D01*
X44987Y-197263D01*
X44114Y-199305D01*
X43677Y-201055D01*
Y-202805D01*
X44114Y-204555D01*
X45206Y-206305D01*
X46516Y-207471D01*
X48044Y-207763D01*
X49572Y-207180D01*
X51101Y-205430D01*
G01X61614Y-205722D02*
X62706Y-206888D01*
X64234Y-207763D01*
X65544D01*
X66854Y-207180D01*
X67727Y-206305D01*
X68164Y-205139D01*
X67946Y-203388D01*
X67072Y-202513D01*
X63142Y-200763D01*
X62269Y-198721D01*
X62706Y-197263D01*
X63579Y-196388D01*
X64889Y-196097D01*
X66199Y-196388D01*
X67509Y-197263D01*
G01X82389Y-196097D02*
Y-207763D01*
G01Y-191430D02*
X81952Y-191138D01*
Y-190555D01*
X82389Y-190263D01*
X82826Y-190555D01*
Y-191138D01*
X82389Y-191430D01*
G01X96832Y-212138D02*
X98361Y-213305D01*
X100107Y-213596D01*
X101635Y-213305D01*
X102946Y-211847D01*
X103819Y-209805D01*
Y-196097D01*
G01Y-198430D02*
X102946Y-197263D01*
X101635Y-196388D01*
X100107Y-196097D01*
X98361Y-196680D01*
X97269Y-197846D01*
X96395Y-199888D01*
X95959Y-201930D01*
X96177Y-203680D01*
X97051Y-205722D01*
X98361Y-207180D01*
X100107Y-207763D01*
X101417Y-207471D01*
X102946Y-206305D01*
X103819Y-205139D01*
G01X113677Y-207763D02*
Y-196097D01*
G01Y-199013D02*
X114551Y-197555D01*
X115861Y-196388D01*
X117607Y-196097D01*
X119135Y-196388D01*
X120446Y-197555D01*
X121101Y-199596D01*
Y-207763D01*
G01X131614Y-199888D02*
X138601D01*
X137946Y-197846D01*
X136854Y-196680D01*
X135326Y-196097D01*
X133797Y-196388D01*
X132487Y-197263D01*
X131614Y-199305D01*
X131177Y-201055D01*
Y-202805D01*
X131614Y-204555D01*
X132706Y-206305D01*
X134016Y-207471D01*
X135544Y-207763D01*
X137072Y-207180D01*
X138601Y-205430D01*
G01X149332Y-207763D02*
Y-196097D01*
G01Y-198430D02*
X150424Y-197263D01*
X151516Y-196388D01*
X153044Y-196097D01*
X154135Y-196388D01*
X155446Y-197263D01*
G01X196089Y-252763D02*
Y-235263D01*
X193469Y-238763D01*
G01Y-252763D02*
X198709D01*
G01X213589Y-235263D02*
X211842Y-235846D01*
X210532Y-237305D01*
X209659Y-239054D01*
X209004Y-241388D01*
X208786Y-244013D01*
X209004Y-246638D01*
X209659Y-248972D01*
X210532Y-250722D01*
X211842Y-252180D01*
X213589Y-252763D01*
X215335Y-252180D01*
X216646Y-250722D01*
X217519Y-248972D01*
X218174Y-246638D01*
X218392Y-244013D01*
X218174Y-241388D01*
X217519Y-239054D01*
X216646Y-237305D01*
X215335Y-235846D01*
X213589Y-235263D01*
G01X227159Y-253346D02*
X235019Y-235263D01*
G01X248589Y-252763D02*
Y-235263D01*
X245969Y-238763D01*
G01Y-252763D02*
X251209D01*
G01X261941Y-245472D02*
X263469Y-243430D01*
X264779Y-242263D01*
X266526Y-241680D01*
X268054Y-242263D01*
X269146Y-243430D01*
X270019Y-245180D01*
X270237Y-247221D01*
X270019Y-248972D01*
X269146Y-250722D01*
X267835Y-252180D01*
X266307Y-252763D01*
X264561Y-252180D01*
X263032Y-250430D01*
X262159Y-247805D01*
X261941Y-244888D01*
X262377Y-241097D01*
X263032Y-239054D01*
X264124Y-237013D01*
X265652Y-235555D01*
X267181Y-235263D01*
X268709Y-235846D01*
X269801Y-237305D01*
G01X279659Y-253346D02*
X287519Y-235263D01*
G01X296941Y-238180D02*
X298251Y-236430D01*
X299779Y-235555D01*
X301526Y-235263D01*
X303709Y-235846D01*
X305237Y-237305D01*
X305674Y-239054D01*
X305456Y-240805D01*
X304582Y-242263D01*
X300216Y-245180D01*
X298251Y-247221D01*
X296941Y-250139D01*
X296504Y-252763D01*
X305674D01*
G01X318589Y-235263D02*
X316842Y-235846D01*
X315532Y-237305D01*
X314659Y-239054D01*
X314004Y-241388D01*
X313786Y-244013D01*
X314004Y-246638D01*
X314659Y-248972D01*
X315532Y-250722D01*
X316842Y-252180D01*
X318589Y-252763D01*
X320335Y-252180D01*
X321646Y-250722D01*
X322519Y-248972D01*
X323174Y-246638D01*
X323392Y-244013D01*
X323174Y-241388D01*
X322519Y-239054D01*
X321646Y-237305D01*
X320335Y-235846D01*
X318589Y-235263D01*
G01X336089Y-252763D02*
Y-235263D01*
X333469Y-238763D01*
G01Y-252763D02*
X338709D01*
G01X349441Y-238180D02*
X350751Y-236430D01*
X352279Y-235555D01*
X354026Y-235263D01*
X356209Y-235846D01*
X357737Y-237305D01*
X358174Y-239054D01*
X357956Y-240805D01*
X357082Y-242263D01*
X352716Y-245180D01*
X350751Y-247221D01*
X349441Y-250139D01*
X349004Y-252763D01*
X358174D01*
G01X243786Y-207763D02*
Y-190263D01*
X248152D01*
X249899Y-191138D01*
X251209Y-192305D01*
X252301Y-194054D01*
X253174Y-196097D01*
X253392Y-199013D01*
X253174Y-201930D01*
X252301Y-203972D01*
X251209Y-205722D01*
X249899Y-206888D01*
X248152Y-207763D01*
X243786D01*
G01X270019D02*
Y-196097D01*
G01Y-198138D02*
X269146Y-196972D01*
X267835Y-196388D01*
X266307Y-196097D01*
X264779Y-196680D01*
X263469Y-197846D01*
X262595Y-199596D01*
X262159Y-201930D01*
X262595Y-204263D01*
X263469Y-206013D01*
X264779Y-207180D01*
X266307Y-207763D01*
X267835Y-207471D01*
X269146Y-206597D01*
X270019Y-205430D01*
G01X283589Y-190263D02*
Y-207763D01*
G01X280532Y-196097D02*
X286646D01*
G01X297814Y-199888D02*
X304801D01*
X304146Y-197846D01*
X303054Y-196680D01*
X301526Y-196097D01*
X299997Y-196388D01*
X298687Y-197263D01*
X297814Y-199305D01*
X297377Y-201055D01*
Y-202805D01*
X297814Y-204555D01*
X298906Y-206305D01*
X300216Y-207471D01*
X301744Y-207763D01*
X303272Y-207180D01*
X304801Y-205430D01*
G01X72800Y93200D02*
X76800D01*
Y85800D01*
G01X45848Y184291D02*
X41848D01*
Y191691D01*
G01X74300Y142900D02*
Y146900D01*
X81700D01*
G01X41851Y184228D02*
X45851D01*
Y176828D01*
G01X60368Y196735D02*
Y200735D01*
X67768D01*
G01X41794Y199158D02*
X45794D01*
Y191758D01*
G01X70706Y183541D02*
Y187541D01*
X78106D01*
G01X60359Y200789D02*
Y204789D01*
X67759D01*
G01X46244Y177674D02*
X54244D01*
Y195274D01*
X46244D01*
Y177674D01*
G01X68455Y192214D02*
Y178214D01*
G01X55455Y192214D02*
X68455D01*
G01X55455Y178214D02*
Y192214D01*
G01X68455Y178214D02*
X55455D01*
G01X59384Y210071D02*
Y196071D01*
G01X46384D02*
Y210071D01*
G01X59384Y196071D02*
X46384D01*
G01X32773Y269007D02*
X28773D01*
Y276407D01*
G01X37107Y269062D02*
X33107D01*
Y276462D01*
G01X58200Y249200D02*
Y253200D01*
X65600D01*
G01X60347Y204909D02*
Y208909D01*
X67747D01*
G01X67758Y213203D02*
Y209203D01*
X60358D01*
G01X46384Y210071D02*
X59384D01*
G01X77963Y230583D02*
X71963D01*
Y237183D01*
G01X72963Y253083D02*
X71963D01*
G01X72963Y265583D02*
X71463D01*
G01X24844Y287417D02*
X36744D01*
G01X24844Y295417D02*
Y287417D01*
G01X36744Y295417D02*
X24844D01*
G01X36744Y287417D02*
Y295417D01*
G01X35144Y291417D02*
X36744Y293017D01*
G01X35144Y291417D02*
X36744Y289817D01*
G01X20900Y315600D02*
X24900D01*
Y308200D01*
G01X37236Y285887D02*
X41236D01*
Y278487D01*
G01X25000Y315500D02*
X29000D01*
Y308100D01*
G01X29100Y315500D02*
X33100D01*
Y308100D01*
G01X71963Y297583D02*
Y303583D01*
X78563D01*
G01X72963Y291583D02*
X71463D01*
G01X72963Y278583D02*
X71963D01*
G01X62883Y387340D02*
Y383340D01*
X55483D01*
G01Y379140D02*
Y383140D01*
X62883D01*
G01X68763Y384683D02*
Y388683D01*
X76163D01*
G01X60473Y445238D02*
Y441238D01*
X53073D01*
G01X53507Y448659D02*
Y452659D01*
X60907D01*
G01X53550Y453007D02*
Y457007D01*
X60950D01*
G01X53531Y478567D02*
Y474567D01*
X46131D01*
G01X41473Y526179D02*
Y530179D01*
X48873D01*
G01X65363Y490683D02*
Y486683D01*
X57963D01*
G01X69367Y521339D02*
X65367D01*
Y528739D01*
G01X61942Y539679D02*
X65942D01*
Y532279D01*
G01X56520Y532394D02*
Y528394D01*
X49120D01*
G01X65065Y521137D02*
X69065D01*
Y513737D01*
G01X65918Y539813D02*
X61918D01*
Y547213D01*
G01X40879Y507972D02*
X48879D01*
Y525572D01*
X40879D01*
Y507972D01*
G01X49653Y527448D02*
X63653D01*
G01X49653Y514448D02*
Y527448D01*
G01X63653Y514448D02*
X49653D01*
G01X63653Y527448D02*
Y514448D01*
G01X46315Y546648D02*
X60315D01*
G01X46315Y533648D02*
Y546648D01*
G01X60315Y533648D02*
X46315D01*
G01X60315Y546648D02*
Y533648D01*
G01X79042Y141571D02*
Y128171D01*
X81042D01*
Y141571D01*
X79042D01*
G01X81100Y223900D02*
Y227900D01*
X88500D01*
G01X82963Y231583D02*
Y229583D01*
G01X108463Y231583D02*
Y229583D01*
G01X95963Y231583D02*
Y230583D01*
G01X121463Y231583D02*
Y230583D01*
G01X146963Y231583D02*
Y230583D01*
G01X133963Y231583D02*
Y229583D01*
G01X115749Y308169D02*
X111749D01*
Y315569D01*
G01X119163Y308003D02*
Y304003D01*
X111763D01*
G01X143963Y303583D02*
Y302583D01*
G01X118463Y303583D02*
Y302583D01*
G01X92963Y303583D02*
Y302583D01*
G01X94863Y399283D02*
Y395283D01*
X87463D01*
G01X96138Y407678D02*
X100138D01*
Y400278D01*
G01X82550Y407763D02*
Y411763D01*
X89950D01*
G01X87163Y392283D02*
X91163D01*
Y384883D01*
G01X87463Y399383D02*
Y403383D01*
X94863D01*
G01X86564Y403439D02*
Y407439D01*
X93964D01*
G01X92076Y416654D02*
X96076D01*
Y409254D01*
G01X95263Y384883D02*
X91263D01*
Y392283D01*
G01X128300Y497800D02*
Y468800D01*
X126300Y470800D01*
X130300D01*
X128300Y468800D01*
G01X147799Y454326D02*
X151799D01*
Y446926D01*
G01X109363Y444783D02*
X105363D01*
Y452183D01*
G01X116163Y476383D02*
X120163D01*
Y468983D01*
G01X96500Y460200D02*
X92500D01*
Y467600D01*
G01X93167Y486194D02*
X89167D01*
Y493594D01*
G01X176555Y267687D02*
Y263687D01*
X169155D01*
G01X176511Y263545D02*
Y259545D01*
X169111D01*
G01X179100Y275900D02*
Y271900D01*
X171700D01*
G01X183278Y242257D02*
X179278D01*
Y249657D01*
G01X179115Y246229D02*
Y242229D01*
X171715D01*
G01X168463Y242583D02*
X166963D01*
G01X168463Y268083D02*
X166963D01*
G01X167963Y255583D02*
X166963D01*
G01X174564Y292017D02*
Y296017D01*
X181964D01*
G01X182008Y291824D02*
Y287824D01*
X174608D01*
G01X161963Y303583D02*
X167963D01*
Y296983D01*
G01Y281083D02*
X166963D01*
G01X238500Y484400D02*
Y480400D01*
X231100D01*
G01X238500Y488500D02*
Y484500D01*
X231100D01*
G01X238500Y480300D02*
Y476300D01*
X231100D01*
G01X238500Y476200D02*
Y472200D01*
X231100D01*
G01X433075Y444474D02*
Y439474D01*
X428075D01*
G01Y467174D02*
X433075D01*
Y462174D01*
G01X405375D02*
Y467174D01*
X410375D01*
G01X414107Y440881D02*
Y437881D01*
G01X424343Y465767D02*
Y468767D01*
G01X406782Y458442D02*
X404782D01*
G01X414638Y469346D02*
Y473346D01*
X422038D01*
G01X426616Y439029D02*
X430616D01*
Y431629D01*
G01X426282Y431718D02*
X422282D01*
Y439118D01*
G01X414632Y473470D02*
Y477470D01*
X422032D01*
G01X433049Y471469D02*
Y467469D01*
X425649D01*
G01X432376Y477966D02*
X414776D01*
G01Y485966D02*
X432376D01*
G01X414776Y477966D02*
Y485966D01*
G01X388609Y458137D02*
Y440537D01*
G01X380609Y458137D02*
X388609D01*
G01X380609Y440537D02*
Y458137D01*
G01X388609Y440537D02*
X380609D01*
G01X431668Y448206D02*
X433668D01*
G01X432376Y485966D02*
Y477966D01*
G01X705758Y449320D02*
Y444320D01*
X700758D01*
G01Y487720D02*
X705758D01*
Y482720D01*
G01X683958D02*
Y487720D01*
X688958D01*
G01X704858Y465970D02*
X707858D01*
G01X695858Y445220D02*
Y442220D01*
G01X681858Y468020D02*
X684858D01*
G01X704858Y456170D02*
X706858D01*
G01X704858Y475820D02*
X706858D01*
G01X682858Y477870D02*
X684858D01*
G01X682858Y458170D02*
X684858D01*
G01X709109Y433023D02*
X705109D01*
Y440423D01*
G01X710245Y483000D02*
Y487000D01*
X717645D01*
G01X710245Y478900D02*
Y482900D01*
X717645D01*
G01X682869Y440211D02*
X686869D01*
Y432811D01*
G01X678738Y440233D02*
X682738D01*
Y432833D01*
G01X691509Y440301D02*
X695509D01*
Y432901D01*
G01X687111Y440212D02*
X691111D01*
Y432812D01*
G01X700367Y433002D02*
X696367D01*
Y440402D01*
G01X704508Y433004D02*
X700508D01*
Y440404D01*
G01X669725Y482651D02*
X674925D01*
G01X669725D02*
Y489651D01*
G01X683125Y482651D02*
X674425D01*
G01X683125Y489651D02*
Y482651D01*
G01X695808Y486820D02*
Y489820D01*
G01X695525Y530891D02*
X683625D01*
G01X695525Y522891D02*
Y530891D01*
G01X683625Y522891D02*
X695525D01*
G01X683625Y530891D02*
Y522891D01*
G01X685225Y526891D02*
X683625Y525291D01*
G01X685225Y526891D02*
X683625Y528491D01*
G01X711642Y541183D02*
X723542D01*
G01X711642Y549183D02*
Y541183D01*
G01X723542Y549183D02*
X711642D01*
G01X662850Y552605D02*
X650950D01*
G01X662850Y544605D02*
Y552605D01*
G01X650950Y544605D02*
X662850D01*
G01X650950Y552605D02*
Y544605D01*
G01X652550Y548605D02*
X650950Y547005D01*
G01X652550Y548605D02*
X650950Y550205D01*
G01X710900Y527600D02*
Y531600D01*
X718300D01*
G01X710900Y523500D02*
Y527500D01*
X718300D01*
G01X707600Y541600D02*
X703600D01*
Y549000D01*
G01Y556600D02*
X707600D01*
Y549200D01*
G01X661300Y531600D02*
X665300D01*
Y524200D01*
G01Y516600D02*
X661300D01*
Y524000D01*
G01X646200Y557500D02*
X650200D01*
Y550100D01*
G01Y542600D02*
X646200D01*
Y550000D01*
G01X707928Y519245D02*
X703928D01*
Y526645D01*
G01X703927Y534127D02*
X707927D01*
Y526727D01*
G01X670705Y543144D02*
X666705D01*
Y550544D01*
G01X666699Y558030D02*
X670699D01*
Y550630D01*
G01X687815Y487878D02*
X683815D01*
Y495278D01*
G01X691996Y487847D02*
X687996D01*
Y495247D01*
G01X700475Y487874D02*
X696475D01*
Y495274D01*
G01X696196Y487947D02*
X692196D01*
Y495347D01*
G01X709296Y487947D02*
X705296D01*
Y495347D01*
G01X704648Y487837D02*
X700648D01*
Y495237D01*
G01X691400Y509400D02*
Y513400D01*
X698800D01*
G01X691800Y547500D02*
Y543500D01*
X684400D01*
G01X670743Y535665D02*
X666743D01*
Y543065D01*
G01X669725Y489651D02*
X677525D01*
G01X676725D02*
X683125D01*
G01X708826Y558695D02*
Y562695D01*
X716226D01*
G01X658767Y565931D02*
Y561931D01*
X651367D01*
G01X699229Y768898D02*
Y764898D01*
X691829D01*
G01X699207Y764804D02*
Y760804D01*
X691807D01*
G01X699220Y840158D02*
Y836158D01*
X691820D01*
G01X699179Y836000D02*
Y832000D01*
X691779D01*
G01X699200Y831925D02*
Y827925D01*
X691800D01*
G01X700030Y802492D02*
Y798492D01*
X692630D01*
G01X699904Y798145D02*
Y794145D01*
X692504D01*
G01X699693Y793967D02*
Y789967D01*
X692293D01*
G01X699398Y789599D02*
Y785599D01*
X691998D01*
G01X699355Y785400D02*
Y781400D01*
X691955D01*
G01X699334Y781285D02*
Y777285D01*
X691934D01*
G01X699313Y777149D02*
Y773149D01*
X691913D01*
G01X699270Y773013D02*
Y769013D01*
X691870D01*
G01X691856Y823792D02*
Y827792D01*
X699256D01*
G01X699347Y856741D02*
Y852741D01*
X691947D01*
G01X699316Y852609D02*
Y848609D01*
X691916D01*
G01X699287Y848395D02*
Y844395D01*
X691887D01*
G01X699268Y844302D02*
Y840302D01*
X691868D01*
G01X691710Y856661D02*
Y852661D01*
X684310D01*
G01X723542Y541183D02*
Y549183D01*
G01X721942Y545183D02*
X723542Y546783D01*
G01X721942Y545183D02*
X723542Y543583D01*
G01X724040Y552596D02*
X728040D01*
Y545196D01*
G01X728045Y537753D02*
X724045D01*
Y545153D01*
G01X732300Y537700D02*
Y533700D01*
X724900D01*
G01X754900Y556700D02*
Y552700D01*
X747500D01*
G01X754900Y552600D02*
Y548600D01*
X747500D01*
G01X754900Y565300D02*
Y561300D01*
X747500D01*
G01X754900Y561200D02*
Y557200D01*
X747500D01*
G01X735982Y848566D02*
Y852566D01*
X743382D01*
G01X735962Y844447D02*
Y848447D01*
X743362D01*
G01X743663Y857068D02*
Y853068D01*
X736263D01*
G01X736100Y857500D02*
Y861500D01*
X743500D01*
G54D18*
G01X50740Y213698D02*
Y214798D01*
G01Y210998D02*
Y212098D01*
G01X44300Y537400D02*
X45400D01*
G01X41600D02*
X42700D01*
G01X60177Y499748D02*
Y501748D01*
G01X120263Y412483D02*
X116263D01*
G01X101563Y452083D02*
X100463D01*
G01X104263D02*
X103163D01*
G01X128310Y462603D02*
X124310D01*
G01X123579Y424373D02*
X127579D01*
G01X104643Y462697D02*
X100643D01*
G01X699500Y521400D02*
X703500D01*
G01X678800D02*
X682800D01*
G01Y532000D02*
X678800D01*
G01X703500D02*
X699500D01*
M02*
